(kicad_pcb
	(version 20260206)
	(generator "pcbnew")
	(generator_version "10.0")
	(general
		(thickness 1.6)
		(legacy_teardrops no)
	)
	(paper "A4")
	(layers
		(0 "F.Cu" signal "TOP")
		(4 "In1.Cu" signal "L2GND")
		(6 "In2.Cu" signal "L3VCC")
		(2 "B.Cu" signal "BOTTOM")
		(9 "F.Adhes" user "F.Adhesive")
		(11 "B.Adhes" user "B.Adhesive")
		(13 "F.Paste" user "Package Geometry/Pastemask Top")
		(15 "B.Paste" user "Package Geometry/Pastemask Bottom")
		(5 "F.SilkS" user "Ref Des/Silkscreen Top")
		(7 "B.SilkS" user "Ref Des/Silkscreen Bottom")
		(1 "F.Mask" user "Board Geometry/Soldermask Top")
		(3 "B.Mask" user "Board Geometry/Soldermask Bottom")
		(17 "Dwgs.User" user "User.Drawings")
		(19 "Cmts.User" user "User.Comments")
		(21 "Eco1.User" user "User.Eco1")
		(23 "Eco2.User" user "User.Eco2")
		(25 "Edge.Cuts" user "Board Geometry/Outline")
		(27 "Margin" user)
		(31 "F.CrtYd" user "Package Geometry/Place Bound Top")
		(29 "B.CrtYd" user "Package Geometry/Place Bound Bottom")
		(35 "F.Fab" user "Ref Des/Assembly Top")
		(33 "B.Fab" user "Ref Des/Assembly Bottom")
	)
	(setup
		(pad_to_mask_clearance 0)
		(allow_soldermask_bridges_in_footprints no)
		(tenting
			(front yes)
			(back yes)
		)
		(covering
			(front no)
			(back no)
		)
		(plugging
			(front no)
			(back no)
		)
		(capping no)
		(filling no)
		(pcbplotparams
			(layerselection 0x00000000_00000000_55555555_5755f5ff)
			(plot_on_all_layers_selection 0x00000000_00000000_00000000_00000000)
			(disableapertmacros no)
			(usegerberextensions no)
			(usegerberattributes yes)
			(usegerberadvancedattributes yes)
			(creategerberjobfile yes)
			(dashed_line_dash_ratio 12)
			(dashed_line_gap_ratio 3)
			(svgprecision 4)
			(plotframeref no)
			(mode 1)
			(useauxorigin no)
			(pdf_front_fp_property_popups yes)
			(pdf_back_fp_property_popups yes)
			(pdf_metadata yes)
			(pdf_single_document no)
			(dxfpolygonmode yes)
			(dxfimperialunits yes)
			(dxfusepcbnewfont yes)
			(psnegative no)
			(psa4output no)
			(plot_black_and_white yes)
			(sketchpadsonfab no)
			(plotpadnumbers no)
			(hidednponfab no)
			(sketchdnponfab yes)
			(crossoutdnponfab yes)
			(subtractmaskfromsilk no)
			(outputformat 1)
			(mirror no)
			(drillshape 1)
			(scaleselection 1)
			(outputdirectory "")
		)
	)
	(footprint ""
		(layer "F.Cu")
		(at 147.169378 -16.997172 -90)
		(property "Reference" "R390"
			(at 0 0 270)
			(layer "F.SilkS")
			(hide yes)
			(effects
				(font
					(size 1.27 1.27)
				)
			)
		)
		(property "Value" "0R2J-2-GP"
			(at 0.064008 -3.993896 270)
			(unlocked yes)
			(layer "F.Fab")
			(hide yes)
			(effects
				(font
					(size 1.016 1.016)
					(thickness 0.1524)
				)
			)
		)
		(property "Device Type" "R402H16"
			(at 0.064008 -5.517896 270)
			(unlocked yes)
			(layer "F.Fab")
			(hide yes)
			(effects
				(font
					(size 1.016 1.016)
					(thickness 0.1524)
				)
			)
		)
		(duplicate_pad_numbers_are_jumpers no)
		(fp_line
			(start -0.508 -0.9398)
			(end -0.508 0.9398)
			(stroke
				(width 0.1524)
				(type default)
			)
			(layer "F.SilkS")
		)
		(fp_line
			(start 0.508 -0.9398)
			(end -0.508 -0.9398)
			(stroke
				(width 0.1524)
				(type default)
			)
			(layer "F.SilkS")
		)
		(fp_rect
			(start -0.508 0.9398)
			(end 0.508 -0.9398)
			(stroke
				(width 0)
				(type default)
			)
			(fill no)
			(layer "F.CrtYd")
		)
		(fp_rect
			(start -0.508 0.9398)
			(end 0.508 -0.9398)
			(stroke
				(width 0)
				(type default)
			)
			(fill no)
			(layer "F.Fab")
		)
		(pad "1" smd custom
			(at 0 -0.4445 270)
			(size 0.1397 0.1397)
			(layers "F.Cu" "F.Mask" "F.Paste")
			(net "TPS2490_DISABLE")
			(options
				(clearance outline)
				(anchor circle)
			)
			(primitives
				(gr_poly
					(pts
						(arc
							(start -0.1778 -0.2794)
							(mid -0.249642 -0.249642)
							(end -0.2794 -0.1778)
						)
						(arc
							(start -0.2794 0.1778)
							(mid -0.249642 0.249642)
							(end -0.1778 0.2794)
						)
						(arc
							(start 0.1778 0.2794)
							(mid 0.249642 0.249642)
							(end 0.2794 0.1778)
						)
						(arc
							(start 0.2794 -0.1778)
							(mid 0.249642 -0.249642)
							(end 0.1778 -0.2794)
						)
					)
					(width 0)
					(fill yes)
				)
			)
		)
		(pad "2" smd custom
			(at 0 0.4445 270)
			(size 0.1397 0.1397)
			(layers "F.Cu" "F.Mask" "F.Paste")
			(net "GND")
			(options
				(clearance outline)
				(anchor circle)
			)
			(primitives
				(gr_poly
					(pts
						(arc
							(start -0.1778 -0.2794)
							(mid -0.249642 -0.249642)
							(end -0.2794 -0.1778)
						)
						(arc
							(start -0.2794 0.1778)
							(mid -0.249642 0.249642)
							(end -0.1778 0.2794)
						)
						(arc
							(start 0.1778 0.2794)
							(mid 0.249642 0.249642)
							(end 0.2794 0.1778)
						)
						(arc
							(start 0.2794 -0.1778)
							(mid 0.249642 -0.249642)
							(end 0.1778 -0.2794)
						)
					)
					(width 0)
					(fill yes)
				)
			)
		)
	)
	(footprint ""
		(layer "F.Cu")
		(at -9.50087 -74.529188 -90)
		(property "Reference" "GF1"
			(at 0 0 270)
			(layer "F.SilkS")
			(hide yes)
			(effects
				(font
					(size 1.27 1.27)
				)
			)
		)
		(property "Value" "GF-36P-24P-GP"
			(at -19.5834 -9.482582 270)
			(unlocked yes)
			(layer "F.Fab")
			(hide yes)
			(effects
				(font
					(size 1.016 1.016)
					(thickness 0.1524)
				)
			)
		)
		(property "Device Type" "GF-36P-24P"
			(at -19.5834 -11.006582 270)
			(unlocked yes)
			(layer "F.Fab")
			(hide yes)
			(effects
				(font
					(size 1.016 1.016)
					(thickness 0.1524)
				)
			)
		)
		(duplicate_pad_numbers_are_jumpers no)
		(fp_rect
			(start -18.6436 2.032)
			(end 47.3964 -8.3312)
			(stroke
				(width 0)
				(type default)
			)
			(fill no)
			(layer "B.CrtYd")
		)
		(fp_rect
			(start -18.6436 2.032)
			(end 47.3964 -8.3312)
			(stroke
				(width 0)
				(type default)
			)
			(fill no)
			(layer "F.CrtYd")
		)
		(fp_rect
			(start -18.6436 2.032)
			(end 47.3964 -8.3312)
			(stroke
				(width 0)
				(type default)
			)
			(fill no)
			(layer "B.Fab")
		)
		(fp_rect
			(start -18.6436 2.032)
			(end 47.3964 -8.3312)
			(stroke
				(width 0)
				(type default)
			)
			(fill no)
			(layer "F.Fab")
		)
		(fp_text user "02 Do not mirror"
			(at 5.969 3.437636 270)
			(unlocked yes)
			(layer "F.Fab")
			(effects
				(font
					(size 1.016 1.016)
					(thickness 0.1524)
				)
				(justify left)
			)
		)
		(pad "P1" smd rect
			(at 40.64 -3.5306 270)
			(size 9.4488 6.2992)
			(drill
				(offset 0 0.381)
			)
			(layers "F.Cu" "F.Mask" "F.Paste")
			(net "P12V")
		)
		(pad "P2" smd rect
			(at 38.2778 -3.9116 270)
			(size 0.0254 0.0254)
			(layers "F.Cu" "F.Mask" "F.Paste")
			(net "P12V")
		)
		(pad "P3" smd rect
			(at 40.64 -3.9116 270)
			(size 0.0254 0.0254)
			(layers "F.Cu" "F.Mask" "F.Paste")
			(net "P12V")
		)
		(pad "P4" smd rect
			(at 43.0022 -3.9116 270)
			(size 0.0254 0.0254)
			(layers "F.Cu" "F.Mask" "F.Paste")
			(net "P12V")
		)
		(pad "P5" smd rect
			(at 30.48 -3.5306 270)
			(size 9.4488 6.2992)
			(drill
				(offset 0 0.381)
			)
			(layers "F.Cu" "F.Mask" "F.Paste")
			(net "P12V")
		)
		(pad "P6" smd rect
			(at 28.1178 -3.9116 270)
			(size 0.0254 0.0254)
			(layers "F.Cu" "F.Mask" "F.Paste")
			(net "P12V")
		)
		(pad "P7" smd rect
			(at 30.48 -3.9116 270)
			(size 0.0254 0.0254)
			(layers "F.Cu" "F.Mask" "F.Paste")
			(net "P12V")
		)
		(pad "P8" smd rect
			(at 32.8422 -3.9116 270)
			(size 0.0254 0.0254)
			(layers "F.Cu" "F.Mask" "F.Paste")
			(net "P12V")
		)
		(pad "P9" smd rect
			(at 20.32 -3.5306 270)
			(size 9.4488 6.2992)
			(drill
				(offset 0 0.381)
			)
			(layers "F.Cu" "F.Mask" "F.Paste")
			(net "GND")
		)
		(pad "P10" smd rect
			(at 17.9578 -3.9116 270)
			(size 0.0254 0.0254)
			(layers "F.Cu" "F.Mask" "F.Paste")
			(net "GND")
		)
		(pad "P11" smd rect
			(at 20.32 -3.9116 270)
			(size 0.0254 0.0254)
			(layers "F.Cu" "F.Mask" "F.Paste")
			(net "GND")
		)
		(pad "P12" smd rect
			(at 22.6822 -3.9116 270)
			(size 0.0254 0.0254)
			(layers "F.Cu" "F.Mask" "F.Paste")
			(net "GND")
		)
		(pad "P13" smd rect
			(at 10.16 -3.5306 270)
			(size 9.4488 6.2992)
			(drill
				(offset 0 0.381)
			)
			(layers "F.Cu" "F.Mask" "F.Paste")
			(net "GND")
		)
		(pad "P14" smd rect
			(at 7.7978 -3.9116 270)
			(size 0.0254 0.0254)
			(layers "F.Cu" "F.Mask" "F.Paste")
			(net "GND")
		)
		(pad "P15" smd rect
			(at 10.16 -3.9116 270)
			(size 0.0254 0.0254)
			(layers "F.Cu" "F.Mask" "F.Paste")
			(net "GND")
		)
		(pad "P16" smd rect
			(at 12.5222 -3.9116 270)
			(size 0.0254 0.0254)
			(layers "F.Cu" "F.Mask" "F.Paste")
			(net "GND")
		)
		(pad "P17" smd rect
			(at 2.6289 -3.5306 270)
			(size 4.191 6.2992)
			(drill
				(offset 0 0.381)
			)
			(layers "F.Cu" "F.Mask" "F.Paste")
			(net "GND")
		)
		(pad "P18" smd rect
			(at 2.6289 -3.9116 270)
			(size 0.0254 0.0254)
			(layers "F.Cu" "F.Mask" "F.Paste")
			(net "GND")
		)
		(pad "P19" smd rect
			(at 2.6289 -3.1496 270)
			(size 4.191 6.2992)
			(layers "F.Cu" "F.Mask" "F.Paste")
			(net "GND")
		)
		(pad "P20" smd rect
			(at 2.6289 -2.7686 270)
			(size 0.0254 0.0254)
			(layers "F.Cu" "F.Mask" "F.Paste")
			(net "GND")
		)
		(pad "P21" smd rect
			(at 10.16 -3.1496 270)
			(size 9.4488 6.2992)
			(layers "F.Cu" "F.Mask" "F.Paste")
			(net "GND")
		)
		(pad "P22" smd rect
			(at 7.7978 -2.7686 270)
			(size 0.0254 0.0254)
			(layers "F.Cu" "F.Mask" "F.Paste")
			(net "GND")
		)
		(pad "P23" smd rect
			(at 10.16 -2.7686 270)
			(size 0.0254 0.0254)
			(layers "F.Cu" "F.Mask" "F.Paste")
			(net "GND")
		)
		(pad "P24" smd rect
			(at 12.5222 -2.7686 270)
			(size 0.0254 0.0254)
			(layers "F.Cu" "F.Mask" "F.Paste")
			(net "GND")
		)
		(pad "P25" smd rect
			(at 20.32 -3.1496 270)
			(size 9.4488 6.2992)
			(layers "F.Cu" "F.Mask" "F.Paste")
			(net "GND")
		)
		(pad "P26" smd rect
			(at 17.9578 -2.7686 270)
			(size 0.0254 0.0254)
			(layers "F.Cu" "F.Mask" "F.Paste")
			(net "GND")
		)
		(pad "P27" smd rect
			(at 20.32 -2.7686 270)
			(size 0.0254 0.0254)
			(layers "F.Cu" "F.Mask" "F.Paste")
			(net "GND")
		)
		(pad "P28" smd rect
			(at 22.6822 -2.7686 270)
			(size 0.0254 0.0254)
			(layers "F.Cu" "F.Mask" "F.Paste")
			(net "GND")
		)
		(pad "P29" smd rect
			(at 30.48 -3.1496 270)
			(size 9.4488 6.2992)
			(layers "F.Cu" "F.Mask" "F.Paste")
			(net "P12V")
		)
		(pad "P30" smd rect
			(at 28.1178 -2.7686 270)
			(size 0.0254 0.0254)
			(layers "F.Cu" "F.Mask" "F.Paste")
			(net "P12V")
		)
		(pad "P31" smd rect
			(at 30.48 -2.7686 270)
			(size 0.0254 0.0254)
			(layers "F.Cu" "F.Mask" "F.Paste")
			(net "P12V")
		)
		(pad "P32" smd rect
			(at 32.8422 -2.7686 270)
			(size 0.0254 0.0254)
			(layers "F.Cu" "F.Mask" "F.Paste")
			(net "P12V")
		)
		(pad "P33" smd rect
			(at 40.64 -3.1496 270)
			(size 9.4488 6.2992)
			(layers "F.Cu" "F.Mask" "F.Paste")
			(net "P12V")
		)
		(pad "P34" smd rect
			(at 38.2778 -2.7686 270)
			(size 0.0254 0.0254)
			(layers "F.Cu" "F.Mask" "F.Paste")
			(net "P12V")
		)
		(pad "P35" smd rect
			(at 40.64 -2.7686 270)
			(size 0.0254 0.0254)
			(layers "F.Cu" "F.Mask" "F.Paste")
			(net "P12V")
		)
		(pad "P36" smd rect
			(at 43.0022 -2.7686 270)
			(size 0.0254 0.0254)
			(layers "F.Cu" "F.Mask" "F.Paste")
			(net "P12V")
		)
		(pad "S1" smd rect
			(at -2.23012 -2.8829 270)
			(size 0.8128 5.0038)
			(drill
				(offset 0 0.381)
			)
			(layers "F.Cu" "F.Mask" "F.Paste")
			(net "GND")
		)
		(pad "S2" smd rect
			(at -3.50012 -2.8829 270)
			(size 0.8128 5.0038)
			(drill
				(offset 0 0.381)
			)
			(layers "F.Cu" "F.Mask" "F.Paste")
			(net "P3V3")
		)
		(pad "S3" smd rect
			(at -4.77012 -2.8829 270)
			(size 0.8128 5.0038)
			(drill
				(offset 0 0.381)
			)
			(layers "F.Cu" "F.Mask" "F.Paste")
			(net "P3V3")
		)
		(pad "S4" smd rect
			(at -6.04012 -2.8829 270)
			(size 0.8128 5.0038)
			(drill
				(offset 0 0.381)
			)
			(layers "F.Cu" "F.Mask" "F.Paste")
			(net "PEER_TRAY_PRESENT")
		)
		(pad "S5" smd rect
			(at -7.31012 -2.8829 270)
			(size 0.8128 5.0038)
			(drill
				(offset 0 0.381)
			)
			(layers "F.Cu" "F.Mask" "F.Paste")
			(net "PWM_EXP_B")
		)
		(pad "S6" smd rect
			(at -8.58012 -2.8829 270)
			(size 0.8128 5.0038)
			(drill
				(offset 0 0.381)
			)
			(layers "F.Cu" "F.Mask" "F.Paste")
			(net "SELF_TRAY_PRESENT")
		)
		(pad "S7" smd rect
			(at -9.85012 -2.8829 270)
			(size 0.8128 5.0038)
			(drill
				(offset 0 0.381)
			)
			(layers "F.Cu" "F.Mask" "F.Paste")
			(net "PWM_EXP_A")
		)
		(pad "S8" smd rect
			(at -11.12012 -2.8829 270)
			(size 0.8128 5.0038)
			(drill
				(offset 0 0.381)
			)
			(layers "F.Cu" "F.Mask" "F.Paste")
			(net "GND")
		)
		(pad "S9" smd rect
			(at -12.39012 -2.8829 270)
			(size 0.8128 5.0038)
			(drill
				(offset 0 0.381)
			)
			(layers "F.Cu" "F.Mask" "F.Paste")
			(net "STRADDLE_I2C_C_SDA")
		)
		(pad "S10" smd rect
			(at -13.66012 -2.8829 270)
			(size 0.8128 5.0038)
			(drill
				(offset 0 0.381)
			)
			(layers "F.Cu" "F.Mask" "F.Paste")
			(net "GND")
		)
		(pad "S11" smd rect
			(at -14.93012 -2.8829 270)
			(size 0.8128 5.0038)
			(drill
				(offset 0 0.381)
			)
			(layers "F.Cu" "F.Mask" "F.Paste")
			(net "STRADDLE_I2C_C_SCL")
		)
		(pad "S12" smd rect
			(at -16.20012 -2.8829 270)
			(size 0.8128 5.0038)
			(drill
				(offset 0 0.381)
			)
			(layers "F.Cu" "F.Mask" "F.Paste")
			(net "GND")
		)
		(pad "S13" smd rect
			(at -16.20012 -2.5019 270)
			(size 0.8128 5.0038)
			(layers "F.Cu" "F.Mask" "F.Paste")
			(net "GND")
		)
		(pad "S14" smd rect
			(at -14.93012 -2.5019 270)
			(size 0.8128 5.0038)
			(layers "F.Cu" "F.Mask" "F.Paste")
			(net "SELF_1A&2A_HB")
		)
		(pad "S15" smd rect
			(at -13.66012 -2.5019 270)
			(size 0.8128 5.0038)
			(layers "F.Cu" "F.Mask" "F.Paste")
			(net "SELF_1B&2B_HB")
		)
		(pad "S16" smd rect
			(at -12.39012 -2.5019 270)
			(size 0.8128 5.0038)
			(layers "F.Cu" "F.Mask" "F.Paste")
			(net "TRAY_ID")
		)
		(pad "S17" smd rect
			(at -11.12012 -2.5019 270)
			(size 0.8128 5.0038)
			(layers "F.Cu" "F.Mask" "F.Paste")
			(net "FCB_HW_REV")
		)
		(pad "S18" smd rect
			(at -9.85012 -2.5019 270)
			(size 0.8128 5.0038)
			(layers "F.Cu" "F.Mask" "F.Paste")
			(net "SD_LATCH_RELEASE")
		)
		(pad "S19" smd rect
			(at -8.58012 -2.5019 270)
			(size 0.8128 5.0038)
			(layers "F.Cu" "F.Mask" "F.Paste")
			(net "GND")
		)
		(pad "S20" smd rect
			(at -7.31012 -2.5019 270)
			(size 0.8128 5.0038)
			(layers "F.Cu" "F.Mask" "F.Paste")
			(net "PEER_1A&2A_HB")
		)
		(pad "S21" smd rect
			(at -6.04012 -2.5019 270)
			(size 0.8128 5.0038)
			(layers "F.Cu" "F.Mask" "F.Paste")
			(net "PEER_1B&2B_HB")
		)
		(pad "S22" smd rect
			(at -4.77012 -2.5019 270)
			(size 0.8128 5.0038)
			(layers "F.Cu" "F.Mask" "F.Paste")
			(net "GND")
		)
		(pad "S23" smd rect
			(at -3.50012 -2.5019 270)
			(size 0.8128 5.0038)
			(layers "F.Cu" "F.Mask" "F.Paste")
			(net "GND")
		)
		(pad "S24" smd rect
			(at -2.23012 -2.5019 270)
			(size 0.8128 5.0038)
			(layers "F.Cu" "F.Mask" "F.Paste")
			(net "P5VA")
		)
		(zone
			(layer "F.Cu")
			(hatch none 0.5)
			(connect_pads
				(clearance 0)
			)
			(min_thickness 0.25)
			(keepout
				(tracks not_allowed)
				(vias allowed)
				(pads allowed)
				(copperpour not_allowed)
				(footprints allowed)
			)
			(placement
				(enabled no)
				(sheetname "")
			)
			(fill
				(thermal_gap 0.5)
				(thermal_bridge_width 0.5)
				(island_removal_mode 0)
			)
			(polygon
				(pts
					(xy -10.51687 -28.092908) (xy -9.50087 -28.092908) (xy -9.50087 -93.025468) (xy -10.51687 -93.025468)
				)
			)
		)
		(zone
			(layer "F.Cu")
			(hatch none 0.5)
			(connect_pads
				(clearance 0)
			)
			(min_thickness 0.25)
			(keepout
				(tracks allowed)
				(vias not_allowed)
				(pads allowed)
				(copperpour not_allowed)
				(footprints allowed)
			)
			(placement
				(enabled no)
				(sheetname "")
			)
			(fill
				(thermal_gap 0.5)
				(thermal_bridge_width 0.5)
				(island_removal_mode 0)
			)
			(polygon
				(pts
					(xy -10.51687 -28.092908) (xy -2.18567 -28.092908) (xy -2.18567 -93.025468) (xy -10.51687 -93.025468)
				)
			)
		)
		(zone
			(layer "B.Cu")
			(hatch none 0.5)
			(connect_pads
				(clearance 0)
			)
			(min_thickness 0.25)
			(keepout
				(tracks not_allowed)
				(vias allowed)
				(pads allowed)
				(copperpour not_allowed)
				(footprints allowed)
			)
			(placement
				(enabled no)
				(sheetname "")
			)
			(fill
				(thermal_gap 0.5)
				(thermal_bridge_width 0.5)
				(island_removal_mode 0)
			)
			(polygon
				(pts
					(xy -10.51687 -28.092908) (xy -9.50087 -28.092908) (xy -9.50087 -93.025468) (xy -10.51687 -93.025468)
				)
			)
		)
		(zone
			(layer "B.Cu")
			(hatch none 0.5)
			(connect_pads
				(clearance 0)
			)
			(min_thickness 0.25)
			(keepout
				(tracks allowed)
				(vias not_allowed)
				(pads allowed)
				(copperpour not_allowed)
				(footprints allowed)
			)
			(placement
				(enabled no)
				(sheetname "")
			)
			(fill
				(thermal_gap 0.5)
				(thermal_bridge_width 0.5)
				(island_removal_mode 0)
			)
			(polygon
				(pts
					(xy -10.51687 -28.092908) (xy -2.18567 -28.092908) (xy -2.18567 -93.025468) (xy -10.51687 -93.025468)
				)
			)
		)
	)
	(footprint ""
		(layer "F.Cu")
		(at 9.372092 -85.835744 90)
		(property "Reference" "R385"
			(at 0 0 90)
			(layer "F.SilkS")
			(hide yes)
			(effects
				(font
					(size 1.27 1.27)
				)
			)
		)
		(property "Value" "0R2J-2-GP"
			(at 0.064008 -3.993896 90)
			(unlocked yes)
			(layer "F.Fab")
			(hide yes)
			(effects
				(font
					(size 1.016 1.016)
					(thickness 0.1524)
				)
			)
		)
		(property "Device Type" "R402H16"
			(at 0.064008 -5.517896 90)
			(unlocked yes)
			(layer "F.Fab")
			(hide yes)
			(effects
				(font
					(size 1.016 1.016)
					(thickness 0.1524)
				)
			)
		)
		(duplicate_pad_numbers_are_jumpers no)
		(fp_line
			(start 0.508 -0.9398)
			(end -0.508 -0.9398)
			(stroke
				(width 0.1524)
				(type default)
			)
			(layer "F.SilkS")
		)
		(fp_line
			(start -0.508 -0.9398)
			(end -0.508 0.9398)
			(stroke
				(width 0.1524)
				(type default)
			)
			(layer "F.SilkS")
		)
		(fp_rect
			(start -0.508 0.9398)
			(end 0.508 -0.9398)
			(stroke
				(width 0)
				(type default)
			)
			(fill no)
			(layer "F.CrtYd")
		)
		(fp_rect
			(start -0.508 0.9398)
			(end 0.508 -0.9398)
			(stroke
				(width 0)
				(type default)
			)
			(fill no)
			(layer "F.Fab")
		)
		(pad "1" smd custom
			(at 0 -0.4445 90)
			(size 0.1397 0.1397)
			(layers "F.Cu" "F.Mask" "F.Paste")
			(net "PWM_EXP_B")
			(options
				(clearance outline)
				(anchor circle)
			)
			(primitives
				(gr_poly
					(pts
						(arc
							(start -0.1778 -0.2794)
							(mid -0.249642 -0.249642)
							(end -0.2794 -0.1778)
						)
						(arc
							(start -0.2794 0.1778)
							(mid -0.249642 0.249642)
							(end -0.1778 0.2794)
						)
						(arc
							(start 0.1778 0.2794)
							(mid 0.249642 0.249642)
							(end 0.2794 0.1778)
						)
						(arc
							(start 0.2794 -0.1778)
							(mid 0.249642 -0.249642)
							(end 0.1778 -0.2794)
						)
					)
					(width 0)
					(fill yes)
				)
			)
		)
		(pad "2" smd custom
			(at 0 0.4445 90)
			(size 0.1397 0.1397)
			(layers "F.Cu" "F.Mask" "F.Paste")
			(net "PWM_EXP_B_OUT")
			(options
				(clearance outline)
				(anchor circle)
			)
			(primitives
				(gr_poly
					(pts
						(arc
							(start -0.1778 -0.2794)
							(mid -0.249642 -0.249642)
							(end -0.2794 -0.1778)
						)
						(arc
							(start -0.2794 0.1778)
							(mid -0.249642 0.249642)
							(end -0.1778 0.2794)
						)
						(arc
							(start 0.1778 0.2794)
							(mid 0.249642 0.249642)
							(end 0.2794 0.1778)
						)
						(arc
							(start 0.2794 -0.1778)
							(mid 0.249642 -0.249642)
							(end 0.1778 -0.2794)
						)
					)
					(width 0)
					(fill yes)
				)
			)
		)
	)
	(footprint ""
		(layer "F.Cu")
		(at 126.659894 -5.999988)
		(property "Reference" "H4"
			(at 0 0 0)
			(layer "F.SilkS")
			(hide yes)
			(effects
				(font
					(size 1.27 1.27)
				)
			)
		)
		(property "Value" "HOLET827X355B355R158-S"
			(at -18.200878 0.089916 0)
			(unlocked yes)
			(layer "F.Fab")
			(hide yes)
			(effects
				(font
					(size 1.016 1.016)
					(thickness 0.1524)
				)
			)
		)
		(property "Device Type" "HOLET827X355B355R158-S"
			(at -18.200878 -1.434084 0)
			(unlocked yes)
			(layer "F.Fab")
			(hide yes)
			(effects
				(font
					(size 1.016 1.016)
					(thickness 0.1524)
				)
			)
		)
		(duplicate_pad_numbers_are_jumpers no)
		(fp_poly
			(pts
				(arc
					(start -4.8133 0)
					(mid 4.8133 0)
					(end -4.8133 0)
				)
			)
			(stroke
				(width 0)
				(type default)
			)
			(fill no)
			(layer "B.CrtYd")
		)
		(fp_poly
			(pts
				(arc
					(start -11.9888 4.8133)
					(mid -16.8021 0)
					(end -11.9888 -4.8133)
				)
				(arc
					(start 0 -4.8133)
					(mid 4.8133 0)
					(end 0 4.8133)
				)
			)
			(stroke
				(width 0)
				(type default)
			)
			(fill no)
			(layer "F.CrtYd")
		)
		(fp_poly
			(pts
				(arc
					(start -4.8133 0)
					(mid 4.8133 0)
					(end -4.8133 0)
				)
			)
			(stroke
				(width 0)
				(type default)
			)
			(fill no)
			(layer "B.Fab")
		)
		(fp_poly
			(pts
				(arc
					(start -11.9888 4.8133)
					(mid -16.8021 0)
					(end -11.9888 -4.8133)
				)
				(arc
					(start 0 -4.8133)
					(mid 4.8133 0)
					(end 0 4.8133)
				)
			)
			(stroke
				(width 0)
				(type default)
			)
			(fill no)
			(layer "F.Fab")
		)
		(pad "1" thru_hole oval
			(at 0 0)
			(size 21.0058 9.017)
			(drill 4.0132
				(offset -5.9944 0)
			)
			(layers "*.Cu" "*.Mask")
			(remove_unused_layers no)
			(net "GND")
			(clearance -7.9883)
			(thermal_gap 0.3048)
			(padstack
				(mode front_inner_back)
				(layer "Inner"
					(shape circle)
					(size 4.4196 4.4196)
					(clearance 0.3048)
				)
				(layer "B.Cu"
					(shape circle)
					(size 9.017 9.017)
					(clearance -1.9939)
				)
			)
		)
	)
	(footprint ""
		(layer "F.Cu")
		(at 9.684512 -95.791528 180)
		(property "Reference" "C357"
			(at 0 0 180)
			(layer "F.SilkS")
			(hide yes)
			(effects
				(font
					(size 1.27 1.27)
				)
			)
		)
		(property "Value" "SC220P50V3JN-GP"
			(at 0 -2.8194 180)
			(unlocked yes)
			(layer "F.Fab")
			(hide yes)
			(effects
				(font
					(size 1.016 1.016)
					(thickness 0.1524)
				)
			)
		)
		(property "Device Type" "C603H36"
			(at 0 -4.3434 180)
			(unlocked yes)
			(layer "F.Fab")
			(hide yes)
			(effects
				(font
					(size 1.016 1.016)
					(thickness 0.1524)
				)
			)
		)
		(duplicate_pad_numbers_are_jumpers no)
		(fp_line
			(start 0.508 0)
			(end -0.508 0)
			(stroke
				(width 0.2032)
				(type default)
			)
			(layer "F.SilkS")
		)
		(fp_rect
			(start -0.5842 1.3335)
			(end 0.5842 -1.3335)
			(stroke
				(width 0)
				(type default)
			)
			(fill no)
			(layer "F.CrtYd")
		)
		(fp_rect
			(start -0.5842 1.3335)
			(end 0.5842 -1.3335)
			(stroke
				(width 0)
				(type default)
			)
			(fill no)
			(layer "F.Fab")
		)
		(pad "1" smd custom
			(at 0 -0.762 180)
			(size 0.2159 0.2159)
			(layers "F.Cu" "F.Mask" "F.Paste")
			(net "I2C_C_SDA")
			(options
				(clearance outline)
				(anchor circle)
			)
			(primitives
				(gr_poly
					(pts
						(arc
							(start -0.3302 -0.4318)
							(mid -0.402042 -0.402042)
							(end -0.4318 -0.3302)
						)
						(arc
							(start -0.4318 0.3302)
							(mid -0.402042 0.402042)
							(end -0.3302 0.4318)
						)
						(arc
							(start 0.3302 0.4318)
							(mid 0.402042 0.402042)
							(end 0.4318 0.3302)
						)
						(arc
							(start 0.4318 -0.3302)
							(mid 0.402042 -0.402042)
							(end 0.3302 -0.4318)
						)
					)
					(width 0)
					(fill yes)
				)
			)
		)
		(pad "2" smd custom
			(at 0 0.762 180)
			(size 0.2159 0.2159)
			(layers "F.Cu" "F.Mask" "F.Paste")
			(net "GND")
			(options
				(clearance outline)
				(anchor circle)
			)
			(primitives
				(gr_poly
					(pts
						(arc
							(start -0.3302 -0.4318)
							(mid -0.402042 -0.402042)
							(end -0.4318 -0.3302)
						)
						(arc
							(start -0.4318 0.3302)
							(mid -0.402042 0.402042)
							(end -0.3302 0.4318)
						)
						(arc
							(start 0.3302 0.4318)
							(mid 0.402042 0.402042)
							(end 0.4318 0.3302)
						)
						(arc
							(start 0.4318 -0.3302)
							(mid 0.402042 -0.402042)
							(end 0.3302 -0.4318)
						)
					)
					(width 0)
					(fill yes)
				)
			)
		)
	)
	(footprint ""
		(layer "F.Cu")
		(at 137.795 -66.286634)
		(property "Reference" "C359"
			(at 0 0 0)
			(layer "F.SilkS")
			(hide yes)
			(effects
				(font
					(size 1.27 1.27)
				)
			)
		)
		(property "Value" "SC220P50V3JN-GP"
			(at 0 -2.8194 0)
			(unlocked yes)
			(layer "F.Fab")
			(hide yes)
			(effects
				(font
					(size 1.016 1.016)
					(thickness 0.1524)
				)
			)
		)
		(property "Device Type" "C603H36"
			(at 0 -4.3434 0)
			(unlocked yes)
			(layer "F.Fab")
			(hide yes)
			(effects
				(font
					(size 1.016 1.016)
					(thickness 0.1524)
				)
			)
		)
		(duplicate_pad_numbers_are_jumpers no)
		(fp_line
			(start 0.508 0)
			(end -0.508 0)
			(stroke
				(width 0.2032)
				(type default)
			)
			(layer "F.SilkS")
		)
		(fp_rect
			(start -0.5842 1.3335)
			(end 0.5842 -1.3335)
			(stroke
				(width 0)
				(type default)
			)
			(fill no)
			(layer "F.CrtYd")
		)
		(fp_rect
			(start -0.5842 1.3335)
			(end 0.5842 -1.3335)
			(stroke
				(width 0)
				(type default)
			)
			(fill no)
			(layer "F.Fab")
		)
		(pad "1" smd custom
			(at 0 -0.762)
			(size 0.2159 0.2159)
			(layers "F.Cu" "F.Mask" "F.Paste")
			(net "I2C_C_BUF_SCL_CONN")
			(options
				(clearance outline)
				(anchor circle)
			)
			(primitives
				(gr_poly
					(pts
						(arc
							(start -0.3302 -0.4318)
							(mid -0.402042 -0.402042)
							(end -0.4318 -0.3302)
						)
						(arc
							(start -0.4318 0.3302)
							(mid -0.402042 0.402042)
							(end -0.3302 0.4318)
						)
						(arc
							(start 0.3302 0.4318)
							(mid 0.402042 0.402042)
							(end 0.4318 0.3302)
						)
						(arc
							(start 0.4318 -0.3302)
							(mid 0.402042 -0.402042)
							(end 0.3302 -0.4318)
						)
					)
					(width 0)
					(fill yes)
				)
			)
		)
		(pad "2" smd custom
			(at 0 0.762)
			(size 0.2159 0.2159)
			(layers "F.Cu" "F.Mask" "F.Paste")
			(net "GND")
			(options
				(clearance outline)
				(anchor circle)
			)
			(primitives
				(gr_poly
					(pts
						(arc
							(start -0.3302 -0.4318)
							(mid -0.402042 -0.402042)
							(end -0.4318 -0.3302)
						)
						(arc
							(start -0.4318 0.3302)
							(mid -0.402042 0.402042)
							(end -0.3302 0.4318)
						)
						(arc
							(start 0.3302 0.4318)
							(mid 0.402042 0.402042)
							(end 0.4318 0.3302)
						)
						(arc
							(start 0.4318 -0.3302)
							(mid 0.402042 -0.402042)
							(end 0.3302 -0.4318)
						)
					)
					(width 0)
					(fill yes)
				)
			)
		)
	)
	(footprint ""
		(layer "F.Cu")
		(at 139.826492 -82.838544)
		(property "Reference" "R378"
			(at 0 0 0)
			(layer "F.SilkS")
			(hide yes)
			(effects
				(font
					(size 1.27 1.27)
				)
			)
		)
		(property "Value" "68R5J-GP"
			(at 0 -8.9535 0)
			(unlocked yes)
			(layer "F.Fab")
			(hide yes)
			(effects
				(font
					(size 1.27 1.016)
					(thickness 0.1524)
				)
			)
		)
		(property "Device Type" "R805H24"
			(at 0 -10.6299 0)
			(unlocked yes)
			(layer "F.Fab")
			(hide yes)
			(effects
				(font
					(size 1.27 1.016)
					(thickness 0.1524)
				)
			)
		)
		(duplicate_pad_numbers_are_jumpers no)
		(fp_line
			(start -0.889 -1.7018)
			(end -0.889 0.2794)
			(stroke
				(width 0.1524)
				(type default)
			)
			(layer "F.SilkS")
		)
		(fp_line
			(start -0.889 0.0762)
			(end -0.889 1.7018)
			(stroke
				(width 0.1524)
				(type default)
			)
			(layer "F.SilkS")
		)
		(fp_line
			(start -0.889 1.7018)
			(end 0.889 1.7018)
			(stroke
				(width 0.1524)
				(type default)
			)
			(layer "F.SilkS")
		)
		(fp_line
			(start 0.889 -1.7018)
			(end -0.889 -1.7018)
			(stroke
				(width 0.1524)
				(type default)
			)
			(layer "F.SilkS")
		)
		(fp_line
			(start 0.889 -1.7018)
			(end 0.889 -0.381)
			(stroke
				(width 0.1524)
				(type default)
			)
			(layer "F.SilkS")
		)
		(fp_line
			(start 0.889 1.7018)
			(end 0.889 -0.508)
			(stroke
				(width 0.1524)
				(type default)
			)
			(layer "F.SilkS")
		)
		(fp_poly
			(pts
				(xy 0.9652 -1.778) (xy 0.9652 1.778) (xy -0.9652 1.778) (xy -0.9652 -1.778)
			)
			(stroke
				(width 0)
				(type default)
			)
			(fill no)
			(layer "F.CrtYd")
		)
		(fp_rect
			(start -0.9652 1.778)
			(end 0.9652 -1.778)
			(stroke
				(width 0)
				(type default)
			)
			(fill no)
			(layer "F.Fab")
		)
		(pad "1" smd rect
			(at 0 -0.9652)
			(size 1.397 1.143)
			(layers "F.Cu" "F.Mask" "F.Paste")
			(net "EMITTER_K")
		)
		(pad "2" smd rect
			(at 0 0.9652)
			(size 1.397 1.143)
			(layers "F.Cu" "F.Mask" "F.Paste")
			(net "GND")
		)
	)
	(footprint ""
		(layer "F.Cu")
		(at 12.977876 -98.81235)
		(property "Reference" "R344"
			(at 0 0 0)
			(layer "F.SilkS")
			(hide yes)
			(effects
				(font
					(size 1.27 1.27)
				)
			)
		)
		(property "Value" "10KR2F-2-GP"
			(at 0.064008 -3.993896 0)
			(unlocked yes)
			(layer "F.Fab")
			(hide yes)
			(effects
				(font
					(size 1.016 1.016)
					(thickness 0.1524)
				)
			)
		)
		(property "Device Type" "R402H16"
			(at 0.064008 -5.517896 0)
			(unlocked yes)
			(layer "F.Fab")
			(hide yes)
			(effects
				(font
					(size 1.016 1.016)
					(thickness 0.1524)
				)
			)
		)
		(duplicate_pad_numbers_are_jumpers no)
		(fp_line
			(start -0.508 -0.9398)
			(end -0.508 0.9398)
			(stroke
				(width 0.1524)
				(type default)
			)
			(layer "F.SilkS")
		)
		(fp_line
			(start 0.508 -0.9398)
			(end -0.508 -0.9398)
			(stroke
				(width 0.1524)
				(type default)
			)
			(layer "F.SilkS")
		)
		(fp_rect
			(start -0.508 0.9398)
			(end 0.508 -0.9398)
			(stroke
				(width 0)
				(type default)
			)
			(fill no)
			(layer "F.CrtYd")
		)
		(fp_rect
			(start -0.508 0.9398)
			(end 0.508 -0.9398)
			(stroke
				(width 0)
				(type default)
			)
			(fill no)
			(layer "F.Fab")
		)
		(pad "1" smd custom
			(at 0 -0.4445)
			(size 0.1397 0.1397)
			(layers "F.Cu" "F.Mask" "F.Paste")
			(net "P3V3")
			(options
				(clearance outline)
				(anchor circle)
			)
			(primitives
				(gr_poly
					(pts
						(arc
							(start -0.1778 -0.2794)
							(mid -0.249642 -0.249642)
							(end -0.2794 -0.1778)
						)
						(arc
							(start -0.2794 0.1778)
							(mid -0.249642 0.249642)
							(end -0.1778 0.2794)
						)
						(arc
							(start 0.1778 0.2794)
							(mid 0.249642 0.249642)
							(end 0.2794 0.1778)
						)
						(arc
							(start 0.2794 -0.1778)
							(mid 0.249642 -0.249642)
							(end 0.1778 -0.2794)
						)
					)
					(width 0)
					(fill yes)
				)
			)
		)
		(pad "2" smd custom
			(at 0 0.4445)
			(size 0.1397 0.1397)
			(layers "F.Cu" "F.Mask" "F.Paste")
			(net "I2C_C_BUF_SDAOUT")
			(options
				(clearance outline)
				(anchor circle)
			)
			(primitives
				(gr_poly
					(pts
						(arc
							(start -0.1778 -0.2794)
							(mid -0.249642 -0.249642)
							(end -0.2794 -0.1778)
						)
						(arc
							(start -0.2794 0.1778)
							(mid -0.249642 0.249642)
							(end -0.1778 0.2794)
						)
						(arc
							(start 0.1778 0.2794)
							(mid 0.249642 0.249642)
							(end 0.2794 0.1778)
						)
						(arc
							(start 0.2794 -0.1778)
							(mid 0.249642 -0.249642)
							(end 0.1778 -0.2794)
						)
					)
					(width 0)
					(fill yes)
				)
			)
		)
	)
	(footprint ""
		(layer "F.Cu")
		(at 17.121632 -99.379786)
		(property "Reference" "TP9"
			(at 0 0 0)
			(layer "F.SilkS")
			(hide yes)
			(effects
				(font
					(size 1.27 1.27)
				)
			)
		)
		(property "Value" "TPAD32-GP"
			(at 0 -3.166364 0)
			(unlocked yes)
			(layer "F.Fab")
			(hide yes)
			(effects
				(font
					(size 1.016 1.016)
					(thickness 0.1524)
				)
			)
		)
		(property "Device Type" "TPAD32"
			(at 0 -4.690618 0)
			(unlocked yes)
			(layer "F.Fab")
			(hide yes)
			(effects
				(font
					(size 1.016 1.016)
					(thickness 0.1524)
				)
			)
		)
		(duplicate_pad_numbers_are_jumpers no)
		(fp_poly
			(pts
				(arc
					(start 0.4064 0)
					(mid -0.4064 0)
					(end 0.4064 0)
				)
			)
			(stroke
				(width 0)
				(type default)
			)
			(fill no)
			(layer "F.CrtYd")
		)
		(fp_poly
			(pts
				(arc
					(start 0.7112 0)
					(mid -0.7112 0)
					(end 0.7112 0)
				)
			)
			(stroke
				(width 0)
				(type default)
			)
			(fill no)
			(layer "F.Fab")
		)
		(pad "1" smd circle
			(at 0 0)
			(size 0.8128 0.8128)
			(layers "F.Cu" "F.Mask" "F.Paste")
			(net "I2C_C_BUF_READY")
		)
	)
	(footprint ""
		(layer "F.Cu")
		(at 120.116092 -47.354744 180)
		(property "Reference" "C355"
			(at 0 0 180)
			(layer "F.SilkS")
			(hide yes)
			(effects
				(font
					(size 1.27 1.27)
				)
			)
		)
		(property "Value" "SC10U25V5KX-GP"
			(at -0.0762 -6.1214 180)
			(unlocked yes)
			(layer "F.Fab")
			(hide yes)
			(effects
				(font
					(size 1.016 1.016)
					(thickness 0.1524)
				)
			)
		)
		(property "Device Type" "C805H56"
			(at -0.0762 -8.1534 180)
			(unlocked yes)
			(layer "F.Fab")
			(hide yes)
			(effects
				(font
					(size 1.016 1.016)
					(thickness 0.1524)
				)
			)
		)
		(duplicate_pad_numbers_are_jumpers no)
		(fp_line
			(start 0.635 0)
			(end -0.635 0)
			(stroke
				(width 0.508)
				(type default)
			)
			(layer "F.SilkS")
		)
		(fp_rect
			(start -0.9652 1.778)
			(end 0.9652 -1.778)
			(stroke
				(width 0)
				(type default)
			)
			(fill no)
			(layer "F.CrtYd")
		)
		(fp_poly
			(pts
				(xy -0.9652 -1.778) (xy 0.9652 -1.778) (xy 0.9652 1.778) (xy -0.9652 1.778)
			)
			(stroke
				(width 0)
				(type default)
			)
			(fill no)
			(layer "F.Fab")
		)
		(pad "1" smd rect
			(at 0 -0.9652 180)
			(size 1.397 1.143)
			(layers "F.Cu" "F.Mask" "F.Paste")
			(net "P12V")
		)
		(pad "2" smd rect
			(at 0 0.9652 180)
			(size 1.397 1.143)
			(layers "F.Cu" "F.Mask" "F.Paste")
			(net "GND")
		)
	)
	(footprint ""
		(layer "F.Cu")
		(at 10.492486 -98.872802 180)
		(property "Reference" "C345"
			(at 0 0 180)
			(layer "F.SilkS")
			(hide yes)
			(effects
				(font
					(size 1.27 1.27)
				)
			)
		)
		(property "Value" "SCD01U50V2KX-1GP"
			(at 1.1811 -2.7051 180)
			(unlocked yes)
			(layer "F.Fab")
			(hide yes)
			(effects
				(font
					(size 1.016 1.016)
					(thickness 0.1524)
				)
			)
		)
		(property "Device Type" "C402H22"
			(at 1.1811 -4.2291 180)
			(unlocked yes)
			(layer "F.Fab")
			(hide yes)
			(effects
				(font
					(size 1.016 1.016)
					(thickness 0.1524)
				)
			)
		)
		(duplicate_pad_numbers_are_jumpers no)
		(fp_rect
			(start -0.4318 0.9525)
			(end 0.4318 -0.9525)
			(stroke
				(width 0)
				(type default)
			)
			(fill no)
			(layer "F.CrtYd")
		)
		(fp_rect
			(start -0.4318 0.9525)
			(end 0.4318 -0.9525)
			(stroke
				(width 0)
				(type default)
			)
			(fill no)
			(layer "F.Fab")
		)
		(pad "1" smd custom
			(at 0 -0.4445 180)
			(size 0.1524 0.1524)
			(layers "F.Cu" "F.Mask" "F.Paste")
			(net "P3V3")
			(options
				(clearance outline)
				(anchor circle)
			)
			(primitives
				(gr_poly
					(pts
						(arc
							(start 0.3048 -0.2032)
							(mid 0.275042 -0.275042)
							(end 0.2032 -0.3048)
						)
						(arc
							(start -0.2032 -0.3048)
							(mid -0.275042 -0.275042)
							(end -0.3048 -0.2032)
						)
						(arc
							(start -0.3048 0.2032)
							(mid -0.275042 0.275042)
							(end -0.2032 0.3048)
						)
						(arc
							(start 0.2032 0.3048)
							(mid 0.275042 0.275042)
							(end 0.3048 0.2032)
						)
					)
					(width 0)
					(fill yes)
				)
			)
		)
		(pad "2" smd custom
			(at 0 0.4445 180)
			(size 0.1524 0.1524)
			(layers "F.Cu" "F.Mask" "F.Paste")
			(net "GND")
			(options
				(clearance outline)
				(anchor circle)
			)
			(primitives
				(gr_poly
					(pts
						(arc
							(start 0.3048 -0.2032)
							(mid 0.275042 -0.275042)
							(end 0.2032 -0.3048)
						)
						(arc
							(start -0.2032 -0.3048)
							(mid -0.275042 -0.275042)
							(end -0.3048 -0.2032)
						)
						(arc
							(start -0.3048 0.2032)
							(mid -0.275042 0.275042)
							(end -0.2032 0.3048)
						)
						(arc
							(start 0.2032 0.3048)
							(mid 0.275042 0.275042)
							(end 0.3048 0.2032)
						)
					)
					(width 0)
					(fill yes)
				)
			)
		)
	)
	(footprint ""
		(layer "F.Cu")
		(at 152.15997 -18.999962 -90)
		(property "Reference" "SW1"
			(at 0 0 270)
			(layer "F.SilkS")
			(hide yes)
			(effects
				(font
					(size 1.27 1.27)
				)
			)
		)
		(property "Value" "SW-SLIDE3P-15-GP"
			(at -6.498844 1.074928 270)
			(unlocked yes)
			(layer "F.Fab")
			(hide yes)
			(effects
				(font
					(size 1.016 1.016)
					(thickness 0.1524)
				)
			)
		)
		(property "Device Type" "SSS-1206"
			(at -6.498844 -0.449072 270)
			(unlocked yes)
			(layer "F.Fab")
			(hide yes)
			(effects
				(font
					(size 1.016 1.016)
					(thickness 0.1524)
				)
			)
		)
		(duplicate_pad_numbers_are_jumpers no)
		(fp_line
			(start -5.2578 1.7526)
			(end -5.2578 -1.7526)
			(stroke
				(width 0.1524)
				(type default)
			)
			(layer "F.SilkS")
		)
		(fp_line
			(start 5.2578 1.7526)
			(end -5.2578 1.7526)
			(stroke
				(width 0.1524)
				(type default)
			)
			(layer "F.SilkS")
		)
		(fp_line
			(start -5.2578 -1.7526)
			(end 5.2578 -1.7526)
			(stroke
				(width 0.1524)
				(type default)
			)
			(layer "F.SilkS")
		)
		(fp_line
			(start 5.2578 -1.7526)
			(end 5.2578 1.7526)
			(stroke
				(width 0.1524)
				(type default)
			)
			(layer "F.SilkS")
		)
		(fp_circle
			(center -1.999996 0.750062)
			(end -1.999996 -0.278638)
			(stroke
				(width 0.3048)
				(type default)
			)
			(fill no)
			(layer "F.SilkS")
		)
		(fp_circle
			(center 1.999996 0.750062)
			(end 1.999996 -0.278638)
			(stroke
				(width 0.3048)
				(type default)
			)
			(fill no)
			(layer "F.SilkS")
		)
		(fp_circle
			(center 0 -0.750062)
			(end 0 -1.778762)
			(stroke
				(width 0.3048)
				(type default)
			)
			(fill no)
			(layer "F.SilkS")
		)
		(fp_rect
			(start -5.0038 1.4986)
			(end 5.0038 -1.4986)
			(stroke
				(width 0)
				(type default)
			)
			(fill no)
			(layer "F.CrtYd")
		)
		(fp_poly
			(pts
				(xy -5.5118 2.0066) (xy -5.5118 -2.0066) (xy 5.5118 -2.0066) (xy 5.5118 -0.00635) (xy 5.0038 -0.00635)
				(xy 5.0038 -1.4986) (xy -5.0038 -1.4986) (xy -5.0038 1.4986) (xy 5.0038 1.4986) (xy 5.0038 0.00635)
				(xy 5.5118 0.00635) (xy 5.5118 2.0066)
			)
			(stroke
				(width 0)
				(type default)
			)
			(fill no)
			(layer "F.CrtYd")
		)
		(fp_rect
			(start -5.5118 2.0066)
			(end 5.5118 -2.0066)
			(stroke
				(width 0)
				(type default)
			)
			(fill no)
			(layer "F.Fab")
		)
		(pad "" np_thru_hole circle
			(at -3.999992 0 270)
			(size 0.254 0.254)
			(drill 0.8636)
			(layers "*.Cu" "*.Mask")
			(clearance 0.6604)
			(thermal_gap 0.6604)
		)
		(pad "" np_thru_hole circle
			(at 3.999992 0 270)
			(size 0.254 0.254)
			(drill 0.8636)
			(layers "*.Cu" "*.Mask")
			(clearance 0.6604)
			(thermal_gap 0.6604)
		)
		(pad "1" thru_hole circle
			(at -1.999996 0.750062 270)
			(size 1.3462 1.3462)
			(drill 0.9398)
			(layers "*.Cu" "*.Mask")
			(remove_unused_layers no)
			(net "TPS2490_EN1")
			(clearance 0.1524)
			(thermal_gap 0.1524)
		)
		(pad "2" thru_hole circle
			(at 0 -0.750062 270)
			(size 1.3462 1.3462)
			(drill 0.9398)
			(layers "*.Cu" "*.Mask")
			(remove_unused_layers no)
			(net "TPS2490_EN2")
			(clearance 0.1524)
			(thermal_gap 0.1524)
		)
		(pad "3" thru_hole circle
			(at 1.999996 0.750062 270)
			(size 1.3462 1.3462)
			(drill 0.9398)
			(layers "*.Cu" "*.Mask")
			(remove_unused_layers no)
			(net "TPS2490_DISABLE")
			(clearance 0.1524)
			(thermal_gap 0.1524)
		)
		(zone
			(layers "F.Cu" "B.Cu" "In1.Cu" "In2.Cu")
			(hatch none 0.5)
			(connect_pads
				(clearance 0)
			)
			(min_thickness 0.25)
			(keepout
				(tracks not_allowed)
				(vias allowed)
				(pads allowed)
				(copperpour not_allowed)
				(footprints allowed)
			)
			(placement
				(enabled no)
				(sheetname "")
			)
			(fill
				(thermal_gap 0.5)
				(thermal_bridge_width 0.5)
				(island_removal_mode 0)
			)
			(polygon
				(pts
					(arc
						(start 152.15997 -22.263354)
						(mid 152.15997 -23.736554)
						(end 152.15997 -22.263354)
					)
				)
			)
		)
		(zone
			(layers "F.Cu" "B.Cu" "In1.Cu" "In2.Cu")
			(hatch none 0.5)
			(connect_pads
				(clearance 0)
			)
			(min_thickness 0.25)
			(keepout
				(tracks not_allowed)
				(vias allowed)
				(pads allowed)
				(copperpour not_allowed)
				(footprints allowed)
			)
			(placement
				(enabled no)
				(sheetname "")
			)
			(fill
				(thermal_gap 0.5)
				(thermal_bridge_width 0.5)
				(island_removal_mode 0)
			)
			(polygon
				(pts
					(arc
						(start 152.15997 -14.26337)
						(mid 152.15997 -15.73657)
						(end 152.15997 -14.26337)
					)
				)
			)
		)
	)
	(footprint ""
		(layer "F.Cu")
		(at 123.85675 -47.164244 180)
		(property "Reference" "TC3"
			(at 0 0 180)
			(layer "F.SilkS")
			(hide yes)
			(effects
				(font
					(size 1.27 1.27)
				)
			)
		)
		(property "Value" "ST68U16VDM-1-GP"
			(at 0 -9.6012 180)
			(unlocked yes)
			(layer "F.Fab")
			(hide yes)
			(effects
				(font
					(size 1.016 1.016)
					(thickness 0.1524)
				)
			)
		)
		(property "Device Type" "CT7343H79"
			(at 0 -11.1252 180)
			(unlocked yes)
			(layer "F.Fab")
			(hide yes)
			(effects
				(font
					(size 1.016 1.016)
					(thickness 0.1524)
				)
			)
		)
		(duplicate_pad_numbers_are_jumpers no)
		(fp_line
			(start 2.286 4.8768)
			(end -2.286 4.8768)
			(stroke
				(width 0.1524)
				(type default)
			)
			(layer "F.SilkS")
		)
		(fp_line
			(start 2.286 2.032)
			(end 2.286 4.8768)
			(stroke
				(width 0.1524)
				(type default)
			)
			(layer "F.SilkS")
		)
		(fp_line
			(start 2.286 -2.032)
			(end 2.286 -4.8768)
			(stroke
				(width 0.1524)
				(type default)
			)
			(layer "F.SilkS")
		)
		(fp_line
			(start 2.286 -4.8768)
			(end -2.286 -4.8768)
			(stroke
				(width 0.1524)
				(type default)
			)
			(layer "F.SilkS")
		)
		(fp_line
			(start 2.1082 -4.699)
			(end -2.1082 -4.699)
			(stroke
				(width 0.508)
				(type default)
			)
			(layer "F.SilkS")
		)
		(fp_line
			(start -2.286 4.8768)
			(end -2.286 2.032)
			(stroke
				(width 0.1524)
				(type default)
			)
			(layer "F.SilkS")
		)
		(fp_line
			(start -2.286 -4.8768)
			(end -2.286 -2.032)
			(stroke
				(width 0.1524)
				(type default)
			)
			(layer "F.SilkS")
		)
		(fp_rect
			(start -2.1463 3.6449)
			(end 2.1463 -3.6449)
			(stroke
				(width 0)
				(type default)
			)
			(fill no)
			(layer "F.CrtYd")
		)
		(fp_poly
			(pts
				(xy -2.54 4.953) (xy -2.54 4.2926) (xy -3.81 4.2926) (xy -3.81 -4.2926) (xy -2.54 -4.2926) (xy -2.54 -4.953)
				(xy 2.54 -4.953) (xy 2.54 -4.2926) (xy 3.81 -4.2926) (xy 3.81 -1.6256) (xy 2.1463 -1.6256) (xy 2.1463 -3.6449)
				(xy -2.1463 -3.6449) (xy -2.1463 3.6449) (xy 2.1463 3.6449) (xy 2.1463 -1.6129) (xy 3.81 -1.6129)
				(xy 3.81 4.2926) (xy 2.54 4.2926) (xy 2.54 4.953)
			)
			(stroke
				(width 0)
				(type default)
			)
			(fill no)
			(layer "F.CrtYd")
		)
		(fp_rect
			(start 2.54 4.2926)
			(end 3.81 -4.2926)
			(stroke
				(width 0)
				(type default)
			)
			(fill no)
			(layer "F.Fab")
		)
		(fp_rect
			(start -2.54 4.953)
			(end 2.54 -4.953)
			(stroke
				(width 0)
				(type default)
			)
			(fill no)
			(layer "F.Fab")
		)
		(fp_rect
			(start -3.81 4.2926)
			(end -2.54 -4.2926)
			(stroke
				(width 0)
				(type default)
			)
			(fill no)
			(layer "F.Fab")
		)
		(pad "1" smd rect
			(at 0 -3.1496 180)
			(size 2.413 2.286)
			(layers "F.Cu" "F.Mask" "F.Paste")
			(net "P12V")
		)
		(pad "2" smd rect
			(at 0 3.1496 180)
			(size 2.413 2.286)
			(layers "F.Cu" "F.Mask" "F.Paste")
			(net "GND")
		)
		(zone
			(layer "F.Cu")
			(hatch none 0.5)
			(connect_pads
				(clearance 0)
			)
			(min_thickness 0.25)
			(keepout
				(tracks allowed)
				(vias not_allowed)
				(pads allowed)
				(copperpour not_allowed)
				(footprints allowed)
			)
			(placement
				(enabled no)
				(sheetname "")
			)
			(fill
				(thermal_gap 0.5)
				(thermal_bridge_width 0.5)
				(island_removal_mode 0)
			)
			(polygon
				(pts
					(xy 122.34545 -45.475144) (xy 122.34545 -42.566844) (xy 125.36805 -42.566844) (xy 125.36805 -45.462444)
					(xy 125.36805 -45.792644) (xy 122.34545 -45.792644)
				)
			)
		)
		(zone
			(layer "F.Cu")
			(hatch none 0.5)
			(connect_pads
				(clearance 0)
			)
			(min_thickness 0.25)
			(keepout
				(tracks allowed)
				(vias not_allowed)
				(pads allowed)
				(copperpour not_allowed)
				(footprints allowed)
			)
			(placement
				(enabled no)
				(sheetname "")
			)
			(fill
				(thermal_gap 0.5)
				(thermal_bridge_width 0.5)
				(island_removal_mode 0)
			)
			(polygon
				(pts
					(xy 125.36805 -51.761644) (xy 122.34545 -51.761644) (xy 122.34545 -48.866044) (xy 122.34545 -48.535844)
					(xy 125.36805 -48.535844) (xy 125.36805 -48.866044)
				)
			)
		)
	)
	(footprint ""
		(layer "F.Cu")
		(at 137.795 -69.080634 180)
		(property "Reference" "C360"
			(at 0 0 180)
			(layer "F.SilkS")
			(hide yes)
			(effects
				(font
					(size 1.27 1.27)
				)
			)
		)
		(property "Value" "SC220P50V3JN-GP"
			(at 0 -2.8194 180)
			(unlocked yes)
			(layer "F.Fab")
			(hide yes)
			(effects
				(font
					(size 1.016 1.016)
					(thickness 0.1524)
				)
			)
		)
		(property "Device Type" "C603H36"
			(at 0 -4.3434 180)
			(unlocked yes)
			(layer "F.Fab")
			(hide yes)
			(effects
				(font
					(size 1.016 1.016)
					(thickness 0.1524)
				)
			)
		)
		(duplicate_pad_numbers_are_jumpers no)
		(fp_line
			(start 0.508 0)
			(end -0.508 0)
			(stroke
				(width 0.2032)
				(type default)
			)
			(layer "F.SilkS")
		)
		(fp_rect
			(start -0.5842 1.3335)
			(end 0.5842 -1.3335)
			(stroke
				(width 0)
				(type default)
			)
			(fill no)
			(layer "F.CrtYd")
		)
		(fp_rect
			(start -0.5842 1.3335)
			(end 0.5842 -1.3335)
			(stroke
				(width 0)
				(type default)
			)
			(fill no)
			(layer "F.Fab")
		)
		(pad "1" smd custom
			(at 0 -0.762 180)
			(size 0.2159 0.2159)
			(layers "F.Cu" "F.Mask" "F.Paste")
			(net "I2C_C_BUF_SDA_CONN")
			(options
				(clearance outline)
				(anchor circle)
			)
			(primitives
				(gr_poly
					(pts
						(arc
							(start -0.3302 -0.4318)
							(mid -0.402042 -0.402042)
							(end -0.4318 -0.3302)
						)
						(arc
							(start -0.4318 0.3302)
							(mid -0.402042 0.402042)
							(end -0.3302 0.4318)
						)
						(arc
							(start 0.3302 0.4318)
							(mid 0.402042 0.402042)
							(end 0.4318 0.3302)
						)
						(arc
							(start 0.4318 -0.3302)
							(mid 0.402042 -0.402042)
							(end 0.3302 -0.4318)
						)
					)
					(width 0)
					(fill yes)
				)
			)
		)
		(pad "2" smd custom
			(at 0 0.762 180)
			(size 0.2159 0.2159)
			(layers "F.Cu" "F.Mask" "F.Paste")
			(net "GND")
			(options
				(clearance outline)
				(anchor circle)
			)
			(primitives
				(gr_poly
					(pts
						(arc
							(start -0.3302 -0.4318)
							(mid -0.402042 -0.402042)
							(end -0.4318 -0.3302)
						)
						(arc
							(start -0.4318 0.3302)
							(mid -0.402042 0.402042)
							(end -0.3302 0.4318)
						)
						(arc
							(start 0.3302 0.4318)
							(mid 0.402042 0.402042)
							(end 0.4318 0.3302)
						)
						(arc
							(start 0.4318 -0.3302)
							(mid 0.402042 -0.402042)
							(end 0.3302 -0.4318)
						)
					)
					(width 0)
					(fill yes)
				)
			)
		)
	)
	(footprint ""
		(layer "F.Cu")
		(at 14.579092 -89.95664 180)
		(property "Reference" "R369"
			(at 0 0 180)
			(layer "F.SilkS")
			(hide yes)
			(effects
				(font
					(size 1.27 1.27)
				)
			)
		)
		(property "Value" "4K7R2J-2-GP"
			(at 0.064008 -3.993896 180)
			(unlocked yes)
			(layer "F.Fab")
			(hide yes)
			(effects
				(font
					(size 1.016 1.016)
					(thickness 0.1524)
				)
			)
		)
		(property "Device Type" "R402H16"
			(at 0.064008 -5.517896 180)
			(unlocked yes)
			(layer "F.Fab")
			(hide yes)
			(effects
				(font
					(size 1.016 1.016)
					(thickness 0.1524)
				)
			)
		)
		(duplicate_pad_numbers_are_jumpers no)
		(fp_line
			(start 0.508 -0.9398)
			(end -0.508 -0.9398)
			(stroke
				(width 0.1524)
				(type default)
			)
			(layer "F.SilkS")
		)
		(fp_line
			(start -0.508 -0.9398)
			(end -0.508 0.9398)
			(stroke
				(width 0.1524)
				(type default)
			)
			(layer "F.SilkS")
		)
		(fp_rect
			(start -0.508 0.9398)
			(end 0.508 -0.9398)
			(stroke
				(width 0)
				(type default)
			)
			(fill no)
			(layer "F.CrtYd")
		)
		(fp_rect
			(start -0.508 0.9398)
			(end 0.508 -0.9398)
			(stroke
				(width 0)
				(type default)
			)
			(fill no)
			(layer "F.Fab")
		)
		(pad "1" smd custom
			(at 0 -0.4445 180)
			(size 0.1397 0.1397)
			(layers "F.Cu" "F.Mask" "F.Paste")
			(net "P3V3")
			(options
				(clearance outline)
				(anchor circle)
			)
			(primitives
				(gr_poly
					(pts
						(arc
							(start -0.1778 -0.2794)
							(mid -0.249642 -0.249642)
							(end -0.2794 -0.1778)
						)
						(arc
							(start -0.2794 0.1778)
							(mid -0.249642 0.249642)
							(end -0.1778 0.2794)
						)
						(arc
							(start 0.1778 0.2794)
							(mid 0.249642 0.249642)
							(end 0.2794 0.1778)
						)
						(arc
							(start 0.2794 -0.1778)
							(mid 0.249642 -0.249642)
							(end 0.1778 -0.2794)
						)
					)
					(width 0)
					(fill yes)
				)
			)
		)
		(pad "2" smd custom
			(at 0 0.4445 180)
			(size 0.1397 0.1397)
			(layers "F.Cu" "F.Mask" "F.Paste")
			(net "I2C_C_BUF_SCLIN")
			(options
				(clearance outline)
				(anchor circle)
			)
			(primitives
				(gr_poly
					(pts
						(arc
							(start -0.1778 -0.2794)
							(mid -0.249642 -0.249642)
							(end -0.2794 -0.1778)
						)
						(arc
							(start -0.2794 0.1778)
							(mid -0.249642 0.249642)
							(end -0.1778 0.2794)
						)
						(arc
							(start 0.1778 0.2794)
							(mid 0.249642 0.249642)
							(end 0.2794 0.1778)
						)
						(arc
							(start 0.2794 -0.1778)
							(mid 0.249642 -0.249642)
							(end 0.1778 -0.2794)
						)
					)
					(width 0)
					(fill yes)
				)
			)
		)
	)
	(footprint ""
		(layer "F.Cu")
		(at 149.659848 -113.999772)
		(property "Reference" "H1"
			(at 0 0 0)
			(layer "F.SilkS")
			(hide yes)
			(effects
				(font
					(size 1.27 1.27)
				)
			)
		)
		(property "Value" "HOLET827X355B355R158-S"
			(at -18.200878 0.089916 0)
			(unlocked yes)
			(layer "F.Fab")
			(hide yes)
			(effects
				(font
					(size 1.016 1.016)
					(thickness 0.1524)
				)
			)
		)
		(property "Device Type" "HOLET827X355B355R158-S"
			(at -18.200878 -1.434084 0)
			(unlocked yes)
			(layer "F.Fab")
			(hide yes)
			(effects
				(font
					(size 1.016 1.016)
					(thickness 0.1524)
				)
			)
		)
		(duplicate_pad_numbers_are_jumpers no)
		(fp_poly
			(pts
				(arc
					(start -4.8133 0)
					(mid 4.8133 0)
					(end -4.8133 0)
				)
			)
			(stroke
				(width 0)
				(type default)
			)
			(fill no)
			(layer "B.CrtYd")
		)
		(fp_poly
			(pts
				(arc
					(start -11.9888 4.8133)
					(mid -16.8021 0)
					(end -11.9888 -4.8133)
				)
				(arc
					(start 0 -4.8133)
					(mid 4.8133 0)
					(end 0 4.8133)
				)
			)
			(stroke
				(width 0)
				(type default)
			)
			(fill no)
			(layer "F.CrtYd")
		)
		(fp_poly
			(pts
				(arc
					(start -4.8133 0)
					(mid 4.8133 0)
					(end -4.8133 0)
				)
			)
			(stroke
				(width 0)
				(type default)
			)
			(fill no)
			(layer "B.Fab")
		)
		(fp_poly
			(pts
				(arc
					(start -11.9888 4.8133)
					(mid -16.8021 0)
					(end -11.9888 -4.8133)
				)
				(arc
					(start 0 -4.8133)
					(mid 4.8133 0)
					(end 0 4.8133)
				)
			)
			(stroke
				(width 0)
				(type default)
			)
			(fill no)
			(layer "F.Fab")
		)
		(pad "1" thru_hole oval
			(at 0 0)
			(size 21.0058 9.017)
			(drill 4.0132
				(offset -5.9944 0)
			)
			(layers "*.Cu" "*.Mask")
			(remove_unused_layers no)
			(net "GND")
			(clearance -7.9883)
			(thermal_gap 0.3048)
			(padstack
				(mode front_inner_back)
				(layer "Inner"
					(shape circle)
					(size 4.4196 4.4196)
					(clearance 0.3048)
				)
				(layer "B.Cu"
					(shape circle)
					(size 9.017 9.017)
					(clearance -1.9939)
				)
			)
		)
	)
	(footprint ""
		(layer "F.Cu")
		(at 2.361438 -49.179226 180)
		(property "Reference" "C349"
			(at 0 0 180)
			(layer "F.SilkS")
			(hide yes)
			(effects
				(font
					(size 1.27 1.27)
				)
			)
		)
		(property "Value" "SC10U25V5KX-GP"
			(at -0.0762 -6.1214 180)
			(unlocked yes)
			(layer "F.Fab")
			(hide yes)
			(effects
				(font
					(size 1.016 1.016)
					(thickness 0.1524)
				)
			)
		)
		(property "Device Type" "C805H56"
			(at -0.0762 -8.1534 180)
			(unlocked yes)
			(layer "F.Fab")
			(hide yes)
			(effects
				(font
					(size 1.016 1.016)
					(thickness 0.1524)
				)
			)
		)
		(duplicate_pad_numbers_are_jumpers no)
		(fp_line
			(start 0.635 0)
			(end -0.635 0)
			(stroke
				(width 0.508)
				(type default)
			)
			(layer "F.SilkS")
		)
		(fp_rect
			(start -0.9652 1.778)
			(end 0.9652 -1.778)
			(stroke
				(width 0)
				(type default)
			)
			(fill no)
			(layer "F.CrtYd")
		)
		(fp_poly
			(pts
				(xy -0.9652 -1.778) (xy 0.9652 -1.778) (xy 0.9652 1.778) (xy -0.9652 1.778)
			)
			(stroke
				(width 0)
				(type default)
			)
			(fill no)
			(layer "F.Fab")
		)
		(pad "1" smd rect
			(at 0 -0.9652 180)
			(size 1.397 1.143)
			(layers "F.Cu" "F.Mask" "F.Paste")
			(net "P12V")
		)
		(pad "2" smd rect
			(at 0 0.9652 180)
			(size 1.397 1.143)
			(layers "F.Cu" "F.Mask" "F.Paste")
			(net "GND")
		)
	)
	(footprint ""
		(layer "F.Cu")
		(at 17.218914 -92.751402 -90)
		(property "Reference" "R485"
			(at 0 0 270)
			(layer "F.SilkS")
			(hide yes)
			(effects
				(font
					(size 1.27 1.27)
				)
			)
		)
		(property "Value" "0R2J-2-GP"
			(at 0.064008 -3.993896 270)
			(unlocked yes)
			(layer "F.Fab")
			(hide yes)
			(effects
				(font
					(size 1.016 1.016)
					(thickness 0.1524)
				)
			)
		)
		(property "Device Type" "R402H16"
			(at 0.064008 -5.517896 270)
			(unlocked yes)
			(layer "F.Fab")
			(hide yes)
			(effects
				(font
					(size 1.016 1.016)
					(thickness 0.1524)
				)
			)
		)
		(duplicate_pad_numbers_are_jumpers no)
		(fp_line
			(start -0.508 -0.9398)
			(end -0.508 0.9398)
			(stroke
				(width 0.1524)
				(type default)
			)
			(layer "F.SilkS")
		)
		(fp_line
			(start 0.508 -0.9398)
			(end -0.508 -0.9398)
			(stroke
				(width 0.1524)
				(type default)
			)
			(layer "F.SilkS")
		)
		(fp_rect
			(start -0.508 0.9398)
			(end 0.508 -0.9398)
			(stroke
				(width 0)
				(type default)
			)
			(fill no)
			(layer "F.CrtYd")
		)
		(fp_rect
			(start -0.508 0.9398)
			(end 0.508 -0.9398)
			(stroke
				(width 0)
				(type default)
			)
			(fill no)
			(layer "F.Fab")
		)
		(pad "1" smd custom
			(at 0 -0.4445 270)
			(size 0.1397 0.1397)
			(layers "F.Cu" "F.Mask" "F.Paste")
			(net "I2C_C_BUF_SCL")
			(options
				(clearance outline)
				(anchor circle)
			)
			(primitives
				(gr_poly
					(pts
						(arc
							(start -0.1778 -0.2794)
							(mid -0.249642 -0.249642)
							(end -0.2794 -0.1778)
						)
						(arc
							(start -0.2794 0.1778)
							(mid -0.249642 0.249642)
							(end -0.1778 0.2794)
						)
						(arc
							(start 0.1778 0.2794)
							(mid 0.249642 0.249642)
							(end 0.2794 0.1778)
						)
						(arc
							(start 0.2794 -0.1778)
							(mid 0.249642 -0.249642)
							(end 0.1778 -0.2794)
						)
					)
					(width 0)
					(fill yes)
				)
			)
		)
		(pad "2" smd custom
			(at 0 0.4445 270)
			(size 0.1397 0.1397)
			(layers "F.Cu" "F.Mask" "F.Paste")
			(net "I2C_C_BUF_SCLIN")
			(options
				(clearance outline)
				(anchor circle)
			)
			(primitives
				(gr_poly
					(pts
						(arc
							(start -0.1778 -0.2794)
							(mid -0.249642 -0.249642)
							(end -0.2794 -0.1778)
						)
						(arc
							(start -0.2794 0.1778)
							(mid -0.249642 0.249642)
							(end -0.1778 0.2794)
						)
						(arc
							(start 0.1778 0.2794)
							(mid 0.249642 0.249642)
							(end 0.2794 0.1778)
						)
						(arc
							(start 0.2794 -0.1778)
							(mid 0.249642 -0.249642)
							(end 0.1778 -0.2794)
						)
					)
					(width 0)
					(fill yes)
				)
			)
		)
	)
	(footprint ""
		(layer "F.Cu")
		(at 134.375144 -79.273908 180)
		(property "Reference" "Q33"
			(at 0 0 180)
			(layer "F.SilkS")
			(hide yes)
			(effects
				(font
					(size 1.27 1.27)
				)
			)
		)
		(property "Value" "MMBT2222A-3-GP"
			(at 0.10287 -10.29843 180)
			(unlocked yes)
			(layer "F.Fab")
			(hide yes)
			(effects
				(font
					(size 1.016 1.016)
					(thickness 0.1524)
				)
			)
		)
		(property "Device Type" "SOT23CBE2D4H44"
			(at 0.10287 -12.20343 180)
			(unlocked yes)
			(layer "F.Fab")
			(hide yes)
			(effects
				(font
					(size 1.016 1.016)
					(thickness 0.1524)
				)
			)
		)
		(duplicate_pad_numbers_are_jumpers no)
		(fp_line
			(start 1.651 1.778)
			(end 1.651 -1.778)
			(stroke
				(width 0.1524)
				(type default)
			)
			(layer "F.SilkS")
		)
		(fp_line
			(start 1.651 -1.778)
			(end -1.651 -1.778)
			(stroke
				(width 0.1524)
				(type default)
			)
			(layer "F.SilkS")
		)
		(fp_line
			(start -1.651 1.778)
			(end 1.651 1.778)
			(stroke
				(width 0.1524)
				(type default)
			)
			(layer "F.SilkS")
		)
		(fp_line
			(start -1.651 -1.778)
			(end -1.651 1.778)
			(stroke
				(width 0.1524)
				(type default)
			)
			(layer "F.SilkS")
		)
		(fp_poly
			(pts
				(xy -1.778 1.8796) (xy -1.778 -1.8796) (xy 1.778 -1.8796) (xy 1.778 1.8796)
			)
			(stroke
				(width 0)
				(type default)
			)
			(fill no)
			(layer "F.CrtYd")
		)
		(fp_poly
			(pts
				(xy -1.778 1.8796) (xy -1.778 -1.8796) (xy 1.778 -1.8796) (xy 1.778 1.8796)
			)
			(stroke
				(width 0)
				(type default)
			)
			(fill no)
			(layer "F.Fab")
		)
		(pad "B" smd custom
			(at -0.98425 0.9525 180)
			(size 0.1905 0.1905)
			(layers "F.Cu" "F.Mask" "F.Paste")
			(net "TRAY_PRESENT_OUT_NET_B")
			(options
				(clearance outline)
				(anchor circle)
			)
			(primitives
				(gr_poly
					(pts
						(arc
							(start -0.1778 0.5715)
							(mid -0.321484 0.511984)
							(end -0.381 0.3683)
						)
						(arc
							(start -0.381 -0.3683)
							(mid -0.321484 -0.511984)
							(end -0.1778 -0.5715)
						)
						(arc
							(start 0.1778 -0.5715)
							(mid 0.321484 -0.511984)
							(end 0.381 -0.3683)
						)
						(arc
							(start 0.381 0.3683)
							(mid 0.321484 0.511984)
							(end 0.1778 0.5715)
						)
					)
					(width 0)
					(fill yes)
				)
			)
		)
		(pad "C" smd custom
			(at 0 -0.9525 180)
			(size 0.1905 0.1905)
			(layers "F.Cu" "F.Mask" "F.Paste")
			(net "TRAY PRESENT_OUT#_C")
			(options
				(clearance outline)
				(anchor circle)
			)
			(primitives
				(gr_poly
					(pts
						(arc
							(start -0.1778 0.5715)
							(mid -0.321484 0.511984)
							(end -0.381 0.3683)
						)
						(arc
							(start -0.381 -0.3683)
							(mid -0.321484 -0.511984)
							(end -0.1778 -0.5715)
						)
						(arc
							(start 0.1778 -0.5715)
							(mid 0.321484 -0.511984)
							(end 0.381 -0.3683)
						)
						(arc
							(start 0.381 0.3683)
							(mid 0.321484 0.511984)
							(end 0.1778 0.5715)
						)
					)
					(width 0)
					(fill yes)
				)
			)
		)
		(pad "E" smd custom
			(at 0.98425 0.9525 180)
			(size 0.1905 0.1905)
			(layers "F.Cu" "F.Mask" "F.Paste")
			(net "GND")
			(options
				(clearance outline)
				(anchor circle)
			)
			(primitives
				(gr_poly
					(pts
						(arc
							(start -0.1778 0.5715)
							(mid -0.321484 0.511984)
							(end -0.381 0.3683)
						)
						(arc
							(start -0.381 -0.3683)
							(mid -0.321484 -0.511984)
							(end -0.1778 -0.5715)
						)
						(arc
							(start 0.1778 -0.5715)
							(mid 0.321484 -0.511984)
							(end 0.381 -0.3683)
						)
						(arc
							(start 0.381 0.3683)
							(mid 0.321484 0.511984)
							(end 0.1778 0.5715)
						)
					)
					(width 0)
					(fill yes)
				)
			)
		)
	)
	(footprint ""
		(layer "F.Cu")
		(at 8.079232 -93.708728 90)
		(property "Reference" "R389"
			(at 0 0 90)
			(layer "F.SilkS")
			(hide yes)
			(effects
				(font
					(size 1.27 1.27)
				)
			)
		)
		(property "Value" "0R2J-2-GP"
			(at 0.064008 -3.993896 90)
			(unlocked yes)
			(layer "F.Fab")
			(hide yes)
			(effects
				(font
					(size 1.016 1.016)
					(thickness 0.1524)
				)
			)
		)
		(property "Device Type" "R402H16"
			(at 0.064008 -5.517896 90)
			(unlocked yes)
			(layer "F.Fab")
			(hide yes)
			(effects
				(font
					(size 1.016 1.016)
					(thickness 0.1524)
				)
			)
		)
		(duplicate_pad_numbers_are_jumpers no)
		(fp_line
			(start 0.508 -0.9398)
			(end -0.508 -0.9398)
			(stroke
				(width 0.1524)
				(type default)
			)
			(layer "F.SilkS")
		)
		(fp_line
			(start -0.508 -0.9398)
			(end -0.508 0.9398)
			(stroke
				(width 0.1524)
				(type default)
			)
			(layer "F.SilkS")
		)
		(fp_rect
			(start -0.508 0.9398)
			(end 0.508 -0.9398)
			(stroke
				(width 0)
				(type default)
			)
			(fill no)
			(layer "F.CrtYd")
		)
		(fp_rect
			(start -0.508 0.9398)
			(end 0.508 -0.9398)
			(stroke
				(width 0)
				(type default)
			)
			(fill no)
			(layer "F.Fab")
		)
		(pad "1" smd custom
			(at 0 -0.4445 90)
			(size 0.1397 0.1397)
			(layers "F.Cu" "F.Mask" "F.Paste")
			(net "STRADDLE_I2C_C_SCL")
			(options
				(clearance outline)
				(anchor circle)
			)
			(primitives
				(gr_poly
					(pts
						(arc
							(start -0.1778 -0.2794)
							(mid -0.249642 -0.249642)
							(end -0.2794 -0.1778)
						)
						(arc
							(start -0.2794 0.1778)
							(mid -0.249642 0.249642)
							(end -0.1778 0.2794)
						)
						(arc
							(start 0.1778 0.2794)
							(mid 0.249642 0.249642)
							(end 0.2794 0.1778)
						)
						(arc
							(start 0.2794 -0.1778)
							(mid 0.249642 -0.249642)
							(end 0.1778 -0.2794)
						)
					)
					(width 0)
					(fill yes)
				)
			)
		)
		(pad "2" smd custom
			(at 0 0.4445 90)
			(size 0.1397 0.1397)
			(layers "F.Cu" "F.Mask" "F.Paste")
			(net "I2C_C_SCL")
			(options
				(clearance outline)
				(anchor circle)
			)
			(primitives
				(gr_poly
					(pts
						(arc
							(start -0.1778 -0.2794)
							(mid -0.249642 -0.249642)
							(end -0.2794 -0.1778)
						)
						(arc
							(start -0.2794 0.1778)
							(mid -0.249642 0.249642)
							(end -0.1778 0.2794)
						)
						(arc
							(start 0.1778 0.2794)
							(mid 0.249642 0.249642)
							(end 0.2794 0.1778)
						)
						(arc
							(start 0.2794 -0.1778)
							(mid 0.249642 -0.249642)
							(end 0.1778 -0.2794)
						)
					)
					(width 0)
					(fill yes)
				)
			)
		)
	)
	(footprint ""
		(layer "F.Cu")
		(at 156.920692 -103.107744)
		(property "Reference" "PR64"
			(at 0 0 0)
			(layer "F.SilkS")
			(hide yes)
			(effects
				(font
					(size 1.27 1.27)
				)
			)
		)
		(property "Value" "0R3J-0-U-GP"
			(at -0.0254 -2.5146 0)
			(unlocked yes)
			(layer "F.Fab")
			(hide yes)
			(effects
				(font
					(size 1.016 1.016)
					(thickness 0.1524)
				)
			)
		)
		(property "Device Type" "R603H22"
			(at -0.0254 -4.0386 0)
			(unlocked yes)
			(layer "F.Fab")
			(hide yes)
			(effects
				(font
					(size 1.016 1.016)
					(thickness 0.1524)
				)
			)
		)
		(duplicate_pad_numbers_are_jumpers no)
		(fp_line
			(start -0.4826 0)
			(end -0.2032 0)
			(stroke
				(width 0.2032)
				(type default)
			)
			(layer "F.SilkS")
		)
		(fp_line
			(start 0.2032 0)
			(end 0.4826 0)
			(stroke
				(width 0.2032)
				(type default)
			)
			(layer "F.SilkS")
		)
		(fp_rect
			(start -0.5842 1.3335)
			(end 0.5842 -1.3335)
			(stroke
				(width 0)
				(type default)
			)
			(fill no)
			(layer "F.CrtYd")
		)
		(fp_rect
			(start -0.5842 1.3335)
			(end 0.5842 -1.3335)
			(stroke
				(width 0)
				(type default)
			)
			(fill no)
			(layer "F.Fab")
		)
		(pad "1" smd custom
			(at 0 -0.762)
			(size 0.2159 0.2159)
			(layers "F.Cu" "F.Mask" "F.Paste")
			(net "P5VA")
			(options
				(clearance outline)
				(anchor circle)
			)
			(primitives
				(gr_poly
					(pts
						(arc
							(start -0.3302 -0.4318)
							(mid -0.402042 -0.402042)
							(end -0.4318 -0.3302)
						)
						(arc
							(start -0.4318 0.3302)
							(mid -0.402042 0.402042)
							(end -0.3302 0.4318)
						)
						(arc
							(start 0.3302 0.4318)
							(mid 0.402042 0.402042)
							(end 0.4318 0.3302)
						)
						(arc
							(start 0.4318 -0.3302)
							(mid 0.402042 -0.402042)
							(end 0.3302 -0.4318)
						)
					)
					(width 0)
					(fill yes)
				)
			)
		)
		(pad "2" smd custom
			(at 0 0.762)
			(size 0.2159 0.2159)
			(layers "F.Cu" "F.Mask" "F.Paste")
			(net "DETECTOR_C")
			(options
				(clearance outline)
				(anchor circle)
			)
			(primitives
				(gr_poly
					(pts
						(arc
							(start -0.3302 -0.4318)
							(mid -0.402042 -0.402042)
							(end -0.4318 -0.3302)
						)
						(arc
							(start -0.4318 0.3302)
							(mid -0.402042 0.402042)
							(end -0.3302 0.4318)
						)
						(arc
							(start 0.3302 0.4318)
							(mid 0.402042 0.402042)
							(end 0.4318 0.3302)
						)
						(arc
							(start 0.4318 -0.3302)
							(mid 0.402042 -0.402042)
							(end 0.3302 -0.4318)
						)
					)
					(width 0)
					(fill yes)
				)
			)
		)
	)
	(footprint ""
		(layer "F.Cu")
		(at 107.061 -47.371 180)
		(property "Reference" "C364"
			(at 0 0 180)
			(layer "F.SilkS")
			(hide yes)
			(effects
				(font
					(size 1.27 1.27)
				)
			)
		)
		(property "Value" "SC47U16V0MX-GP"
			(at -0.00254 -4.78536 180)
			(unlocked yes)
			(layer "F.Fab")
			(hide yes)
			(effects
				(font
					(size 1.016 1.016)
					(thickness 0.1524)
				)
			)
		)
		(property "Device Type" "C1210H107"
			(at -0.00254 -6.38048 180)
			(unlocked yes)
			(layer "F.Fab")
			(hide yes)
			(effects
				(font
					(size 1.016 1.016)
					(thickness 0.1524)
				)
			)
		)
		(duplicate_pad_numbers_are_jumpers no)
		(fp_line
			(start 1.5748 2.3368)
			(end 1.5748 0.762)
			(stroke
				(width 0.1524)
				(type default)
			)
			(layer "F.SilkS")
		)
		(fp_line
			(start 1.5748 -0.762)
			(end 1.5748 -2.3368)
			(stroke
				(width 0.1524)
				(type default)
			)
			(layer "F.SilkS")
		)
		(fp_line
			(start 1.5748 -2.3368)
			(end -1.5748 -2.3368)
			(stroke
				(width 0.1524)
				(type default)
			)
			(layer "F.SilkS")
		)
		(fp_line
			(start -1.5748 2.3368)
			(end 1.5748 2.3368)
			(stroke
				(width 0.1524)
				(type default)
			)
			(layer "F.SilkS")
		)
		(fp_line
			(start -1.5748 0.762)
			(end -1.5748 2.3368)
			(stroke
				(width 0.1524)
				(type default)
			)
			(layer "F.SilkS")
		)
		(fp_line
			(start -1.5748 -2.3368)
			(end -1.5748 -0.762)
			(stroke
				(width 0.1524)
				(type default)
			)
			(layer "F.SilkS")
		)
		(fp_rect
			(start -1.651 2.413)
			(end 1.651 -2.413)
			(stroke
				(width 0)
				(type default)
			)
			(fill no)
			(layer "F.CrtYd")
		)
		(fp_poly
			(pts
				(xy 1.651 2.413) (xy 1.651 -2.413) (xy -1.651 -2.413) (xy -1.651 2.413)
			)
			(stroke
				(width 0)
				(type default)
			)
			(fill no)
			(layer "F.Fab")
		)
		(pad "1" smd rect
			(at 0 -1.4732 180)
			(size 2.794 1.397)
			(layers "F.Cu" "F.Mask" "F.Paste")
			(net "P12V")
		)
		(pad "2" smd rect
			(at 0 1.4732 180)
			(size 2.794 1.397)
			(layers "F.Cu" "F.Mask" "F.Paste")
			(net "GND")
		)
	)
	(footprint ""
		(layer "F.Cu")
		(at 11.634978 -99.280472 180)
		(property "Reference" "C344"
			(at 0 0 180)
			(layer "F.SilkS")
			(hide yes)
			(effects
				(font
					(size 1.27 1.27)
				)
			)
		)
		(property "Value" "SCD1U50V3KX-GP"
			(at 0 -2.8194 180)
			(unlocked yes)
			(layer "F.Fab")
			(hide yes)
			(effects
				(font
					(size 1.016 1.016)
					(thickness 0.1524)
				)
			)
		)
		(property "Device Type" "C603H36"
			(at 0 -4.3434 180)
			(unlocked yes)
			(layer "F.Fab")
			(hide yes)
			(effects
				(font
					(size 1.016 1.016)
					(thickness 0.1524)
				)
			)
		)
		(duplicate_pad_numbers_are_jumpers no)
		(fp_line
			(start 0.508 0)
			(end -0.508 0)
			(stroke
				(width 0.2032)
				(type default)
			)
			(layer "F.SilkS")
		)
		(fp_rect
			(start -0.5842 1.3335)
			(end 0.5842 -1.3335)
			(stroke
				(width 0)
				(type default)
			)
			(fill no)
			(layer "F.CrtYd")
		)
		(fp_rect
			(start -0.5842 1.3335)
			(end 0.5842 -1.3335)
			(stroke
				(width 0)
				(type default)
			)
			(fill no)
			(layer "F.Fab")
		)
		(pad "1" smd custom
			(at 0 -0.762 180)
			(size 0.2159 0.2159)
			(layers "F.Cu" "F.Mask" "F.Paste")
			(net "P3V3")
			(options
				(clearance outline)
				(anchor circle)
			)
			(primitives
				(gr_poly
					(pts
						(arc
							(start -0.3302 -0.4318)
							(mid -0.402042 -0.402042)
							(end -0.4318 -0.3302)
						)
						(arc
							(start -0.4318 0.3302)
							(mid -0.402042 0.402042)
							(end -0.3302 0.4318)
						)
						(arc
							(start 0.3302 0.4318)
							(mid 0.402042 0.402042)
							(end 0.4318 0.3302)
						)
						(arc
							(start 0.4318 -0.3302)
							(mid 0.402042 -0.402042)
							(end 0.3302 -0.4318)
						)
					)
					(width 0)
					(fill yes)
				)
			)
		)
		(pad "2" smd custom
			(at 0 0.762 180)
			(size 0.2159 0.2159)
			(layers "F.Cu" "F.Mask" "F.Paste")
			(net "GND")
			(options
				(clearance outline)
				(anchor circle)
			)
			(primitives
				(gr_poly
					(pts
						(arc
							(start -0.3302 -0.4318)
							(mid -0.402042 -0.402042)
							(end -0.4318 -0.3302)
						)
						(arc
							(start -0.4318 0.3302)
							(mid -0.402042 0.402042)
							(end -0.3302 0.4318)
						)
						(arc
							(start 0.3302 0.4318)
							(mid 0.402042 0.402042)
							(end 0.4318 0.3302)
						)
						(arc
							(start 0.4318 -0.3302)
							(mid 0.402042 -0.402042)
							(end 0.3302 -0.4318)
						)
					)
					(width 0)
					(fill yes)
				)
			)
		)
	)
	(footprint ""
		(layer "F.Cu")
		(at 134.368794 -75.439778 180)
		(property "Reference" "Q34"
			(at 0 0 180)
			(layer "F.SilkS")
			(hide yes)
			(effects
				(font
					(size 1.27 1.27)
				)
			)
		)
		(property "Value" "2N7002-11-GP"
			(at 0.127 -8.9662 180)
			(unlocked yes)
			(layer "F.Fab")
			(hide yes)
			(effects
				(font
					(size 1.016 1.016)
					(thickness 0.1524)
				)
			)
		)
		(property "Device Type" "SOT23DGS2D4H44"
			(at 0.127 -10.4902 180)
			(unlocked yes)
			(layer "F.Fab")
			(hide yes)
			(effects
				(font
					(size 1.016 1.016)
					(thickness 0.1524)
				)
			)
		)
		(duplicate_pad_numbers_are_jumpers no)
		(fp_line
			(start 1.651 1.778)
			(end 1.651 -1.778)
			(stroke
				(width 0.1524)
				(type default)
			)
			(layer "F.SilkS")
		)
		(fp_line
			(start 1.651 -1.778)
			(end -1.651 -1.778)
			(stroke
				(width 0.1524)
				(type default)
			)
			(layer "F.SilkS")
		)
		(fp_line
			(start -1.651 1.778)
			(end 1.651 1.778)
			(stroke
				(width 0.1524)
				(type default)
			)
			(layer "F.SilkS")
		)
		(fp_line
			(start -1.651 -1.778)
			(end -1.651 1.778)
			(stroke
				(width 0.1524)
				(type default)
			)
			(layer "F.SilkS")
		)
		(fp_poly
			(pts
				(xy -1.778 1.8796) (xy -1.778 -1.8796) (xy 1.778 -1.8796) (xy 1.778 1.8796)
			)
			(stroke
				(width 0)
				(type default)
			)
			(fill no)
			(layer "F.CrtYd")
		)
		(fp_poly
			(pts
				(xy -1.778 1.8796) (xy -1.778 -1.8796) (xy 1.778 -1.8796) (xy 1.778 1.8796)
			)
			(stroke
				(width 0)
				(type default)
			)
			(fill no)
			(layer "F.Fab")
		)
		(pad "D" smd custom
			(at 0 -0.9525 180)
			(size 0.1905 0.1905)
			(layers "F.Cu" "F.Mask" "F.Paste")
			(net "SELF_TRAY_PRESENT")
			(options
				(clearance outline)
				(anchor circle)
			)
			(primitives
				(gr_poly
					(pts
						(arc
							(start -0.1778 0.5715)
							(mid -0.321484 0.511984)
							(end -0.381 0.3683)
						)
						(arc
							(start -0.381 -0.3683)
							(mid -0.321484 -0.511984)
							(end -0.1778 -0.5715)
						)
						(arc
							(start 0.1778 -0.5715)
							(mid 0.321484 -0.511984)
							(end 0.381 -0.3683)
						)
						(arc
							(start 0.381 0.3683)
							(mid 0.321484 0.511984)
							(end 0.1778 0.5715)
						)
					)
					(width 0)
					(fill yes)
				)
			)
		)
		(pad "G" smd custom
			(at -0.98425 0.9525 180)
			(size 0.1905 0.1905)
			(layers "F.Cu" "F.Mask" "F.Paste")
			(net "TRAY_MOSFET_G")
			(options
				(clearance outline)
				(anchor circle)
			)
			(primitives
				(gr_poly
					(pts
						(arc
							(start -0.1778 0.5715)
							(mid -0.321484 0.511984)
							(end -0.381 0.3683)
						)
						(arc
							(start -0.381 -0.3683)
							(mid -0.321484 -0.511984)
							(end -0.1778 -0.5715)
						)
						(arc
							(start 0.1778 -0.5715)
							(mid 0.321484 -0.511984)
							(end 0.381 -0.3683)
						)
						(arc
							(start 0.381 0.3683)
							(mid 0.321484 0.511984)
							(end 0.1778 0.5715)
						)
					)
					(width 0)
					(fill yes)
				)
			)
		)
		(pad "S" smd custom
			(at 0.98425 0.9525 180)
			(size 0.1905 0.1905)
			(layers "F.Cu" "F.Mask" "F.Paste")
			(net "GND")
			(options
				(clearance outline)
				(anchor circle)
			)
			(primitives
				(gr_poly
					(pts
						(arc
							(start -0.1778 0.5715)
							(mid -0.321484 0.511984)
							(end -0.381 0.3683)
						)
						(arc
							(start -0.381 -0.3683)
							(mid -0.321484 -0.511984)
							(end -0.1778 -0.5715)
						)
						(arc
							(start 0.1778 -0.5715)
							(mid 0.321484 -0.511984)
							(end 0.381 -0.3683)
						)
						(arc
							(start 0.381 0.3683)
							(mid 0.321484 0.511984)
							(end 0.1778 0.5715)
						)
					)
					(width 0)
					(fill yes)
				)
			)
		)
	)
	(footprint ""
		(layer "F.Cu")
		(at 156.972 -18.923)
		(property "Reference" "R483"
			(at 0 0 0)
			(layer "F.SilkS")
			(hide yes)
			(effects
				(font
					(size 1.27 1.27)
				)
			)
		)
		(property "Value" "2KR3F-L-GP"
			(at -0.0254 -2.5146 0)
			(unlocked yes)
			(layer "F.Fab")
			(hide yes)
			(effects
				(font
					(size 1.016 1.016)
					(thickness 0.1524)
				)
			)
		)
		(property "Device Type" "R603H22"
			(at -0.0254 -4.0386 0)
			(unlocked yes)
			(layer "F.Fab")
			(hide yes)
			(effects
				(font
					(size 1.016 1.016)
					(thickness 0.1524)
				)
			)
		)
		(duplicate_pad_numbers_are_jumpers no)
		(fp_line
			(start -0.4826 0)
			(end -0.2032 0)
			(stroke
				(width 0.2032)
				(type default)
			)
			(layer "F.SilkS")
		)
		(fp_line
			(start 0.2032 0)
			(end 0.4826 0)
			(stroke
				(width 0.2032)
				(type default)
			)
			(layer "F.SilkS")
		)
		(fp_rect
			(start -0.5842 1.3335)
			(end 0.5842 -1.3335)
			(stroke
				(width 0)
				(type default)
			)
			(fill no)
			(layer "F.CrtYd")
		)
		(fp_rect
			(start -0.5842 1.3335)
			(end 0.5842 -1.3335)
			(stroke
				(width 0)
				(type default)
			)
			(fill no)
			(layer "F.Fab")
		)
		(pad "1" smd custom
			(at 0 -0.762)
			(size 0.2159 0.2159)
			(layers "F.Cu" "F.Mask" "F.Paste")
			(net "P12V")
			(options
				(clearance outline)
				(anchor circle)
			)
			(primitives
				(gr_poly
					(pts
						(arc
							(start -0.3302 -0.4318)
							(mid -0.402042 -0.402042)
							(end -0.4318 -0.3302)
						)
						(arc
							(start -0.4318 0.3302)
							(mid -0.402042 0.402042)
							(end -0.3302 0.4318)
						)
						(arc
							(start 0.3302 0.4318)
							(mid 0.402042 0.402042)
							(end 0.4318 0.3302)
						)
						(arc
							(start 0.4318 -0.3302)
							(mid 0.402042 -0.402042)
							(end 0.3302 -0.4318)
						)
					)
					(width 0)
					(fill yes)
				)
			)
		)
		(pad "2" smd custom
			(at 0 0.762)
			(size 0.2159 0.2159)
			(layers "F.Cu" "F.Mask" "F.Paste")
			(net "TPS2490_LED")
			(options
				(clearance outline)
				(anchor circle)
			)
			(primitives
				(gr_poly
					(pts
						(arc
							(start -0.3302 -0.4318)
							(mid -0.402042 -0.402042)
							(end -0.4318 -0.3302)
						)
						(arc
							(start -0.4318 0.3302)
							(mid -0.402042 0.402042)
							(end -0.3302 0.4318)
						)
						(arc
							(start 0.3302 0.4318)
							(mid 0.402042 0.402042)
							(end 0.4318 0.3302)
						)
						(arc
							(start 0.4318 -0.3302)
							(mid 0.402042 -0.402042)
							(end 0.3302 -0.4318)
						)
					)
					(width 0)
					(fill yes)
				)
			)
		)
	)
	(footprint ""
		(layer "F.Cu")
		(at 17.2339 -96.071944 90)
		(property "Reference" "R487"
			(at 0 0 90)
			(layer "F.SilkS")
			(hide yes)
			(effects
				(font
					(size 1.27 1.27)
				)
			)
		)
		(property "Value" "0R2J-2-GP"
			(at 0.064008 -3.993896 90)
			(unlocked yes)
			(layer "F.Fab")
			(hide yes)
			(effects
				(font
					(size 1.016 1.016)
					(thickness 0.1524)
				)
			)
		)
		(property "Device Type" "R402H16"
			(at 0.064008 -5.517896 90)
			(unlocked yes)
			(layer "F.Fab")
			(hide yes)
			(effects
				(font
					(size 1.016 1.016)
					(thickness 0.1524)
				)
			)
		)
		(duplicate_pad_numbers_are_jumpers no)
		(fp_line
			(start 0.508 -0.9398)
			(end -0.508 -0.9398)
			(stroke
				(width 0.1524)
				(type default)
			)
			(layer "F.SilkS")
		)
		(fp_line
			(start -0.508 -0.9398)
			(end -0.508 0.9398)
			(stroke
				(width 0.1524)
				(type default)
			)
			(layer "F.SilkS")
		)
		(fp_rect
			(start -0.508 0.9398)
			(end 0.508 -0.9398)
			(stroke
				(width 0)
				(type default)
			)
			(fill no)
			(layer "F.CrtYd")
		)
		(fp_rect
			(start -0.508 0.9398)
			(end 0.508 -0.9398)
			(stroke
				(width 0)
				(type default)
			)
			(fill no)
			(layer "F.Fab")
		)
		(pad "1" smd custom
			(at 0 -0.4445 90)
			(size 0.1397 0.1397)
			(layers "F.Cu" "F.Mask" "F.Paste")
			(net "I2C_C_BUF_SDAIN")
			(options
				(clearance outline)
				(anchor circle)
			)
			(primitives
				(gr_poly
					(pts
						(arc
							(start -0.1778 -0.2794)
							(mid -0.249642 -0.249642)
							(end -0.2794 -0.1778)
						)
						(arc
							(start -0.2794 0.1778)
							(mid -0.249642 0.249642)
							(end -0.1778 0.2794)
						)
						(arc
							(start 0.1778 0.2794)
							(mid 0.249642 0.249642)
							(end 0.2794 0.1778)
						)
						(arc
							(start 0.2794 -0.1778)
							(mid 0.249642 -0.249642)
							(end 0.1778 -0.2794)
						)
					)
					(width 0)
					(fill yes)
				)
			)
		)
		(pad "2" smd custom
			(at 0 0.4445 90)
			(size 0.1397 0.1397)
			(layers "F.Cu" "F.Mask" "F.Paste")
			(net "I2C_C_BUF_SDA")
			(options
				(clearance outline)
				(anchor circle)
			)
			(primitives
				(gr_poly
					(pts
						(arc
							(start -0.1778 -0.2794)
							(mid -0.249642 -0.249642)
							(end -0.2794 -0.1778)
						)
						(arc
							(start -0.2794 0.1778)
							(mid -0.249642 0.249642)
							(end -0.1778 0.2794)
						)
						(arc
							(start 0.1778 0.2794)
							(mid 0.249642 0.249642)
							(end 0.2794 0.1778)
						)
						(arc
							(start 0.2794 -0.1778)
							(mid 0.249642 -0.249642)
							(end 0.1778 -0.2794)
						)
					)
					(width 0)
					(fill yes)
				)
			)
		)
	)
	(footprint ""
		(layer "F.Cu")
		(at 17.233138 -94.990666 90)
		(property "Reference" "R481"
			(at 0 0 90)
			(layer "F.SilkS")
			(hide yes)
			(effects
				(font
					(size 1.27 1.27)
				)
			)
		)
		(property "Value" "0R2J-2-GP"
			(at 0.064008 -3.993896 90)
			(unlocked yes)
			(layer "F.Fab")
			(hide yes)
			(effects
				(font
					(size 1.016 1.016)
					(thickness 0.1524)
				)
			)
		)
		(property "Device Type" "R402H16"
			(at 0.064008 -5.517896 90)
			(unlocked yes)
			(layer "F.Fab")
			(hide yes)
			(effects
				(font
					(size 1.016 1.016)
					(thickness 0.1524)
				)
			)
		)
		(duplicate_pad_numbers_are_jumpers no)
		(fp_line
			(start 0.508 -0.9398)
			(end -0.508 -0.9398)
			(stroke
				(width 0.1524)
				(type default)
			)
			(layer "F.SilkS")
		)
		(fp_line
			(start -0.508 -0.9398)
			(end -0.508 0.9398)
			(stroke
				(width 0.1524)
				(type default)
			)
			(layer "F.SilkS")
		)
		(fp_rect
			(start -0.508 0.9398)
			(end 0.508 -0.9398)
			(stroke
				(width 0)
				(type default)
			)
			(fill no)
			(layer "F.CrtYd")
		)
		(fp_rect
			(start -0.508 0.9398)
			(end 0.508 -0.9398)
			(stroke
				(width 0)
				(type default)
			)
			(fill no)
			(layer "F.Fab")
		)
		(pad "1" smd custom
			(at 0 -0.4445 90)
			(size 0.1397 0.1397)
			(layers "F.Cu" "F.Mask" "F.Paste")
			(net "I2C_C_SDA")
			(options
				(clearance outline)
				(anchor circle)
			)
			(primitives
				(gr_poly
					(pts
						(arc
							(start -0.1778 -0.2794)
							(mid -0.249642 -0.249642)
							(end -0.2794 -0.1778)
						)
						(arc
							(start -0.2794 0.1778)
							(mid -0.249642 0.249642)
							(end -0.1778 0.2794)
						)
						(arc
							(start 0.1778 0.2794)
							(mid 0.249642 0.249642)
							(end 0.2794 0.1778)
						)
						(arc
							(start 0.2794 -0.1778)
							(mid 0.249642 -0.249642)
							(end 0.1778 -0.2794)
						)
					)
					(width 0)
					(fill yes)
				)
			)
		)
		(pad "2" smd custom
			(at 0 0.4445 90)
			(size 0.1397 0.1397)
			(layers "F.Cu" "F.Mask" "F.Paste")
			(net "I2C_C_BUF_SDA")
			(options
				(clearance outline)
				(anchor circle)
			)
			(primitives
				(gr_poly
					(pts
						(arc
							(start -0.1778 -0.2794)
							(mid -0.249642 -0.249642)
							(end -0.2794 -0.1778)
						)
						(arc
							(start -0.2794 0.1778)
							(mid -0.249642 0.249642)
							(end -0.1778 0.2794)
						)
						(arc
							(start 0.1778 0.2794)
							(mid 0.249642 0.249642)
							(end 0.2794 0.1778)
						)
						(arc
							(start 0.2794 -0.1778)
							(mid 0.249642 -0.249642)
							(end 0.1778 -0.2794)
						)
					)
					(width 0)
					(fill yes)
				)
			)
		)
	)
	(footprint ""
		(layer "F.Cu")
		(at 117.348 -47.371 180)
		(property "Reference" "C361"
			(at 0 0 180)
			(layer "F.SilkS")
			(hide yes)
			(effects
				(font
					(size 1.27 1.27)
				)
			)
		)
		(property "Value" "SC47U16V0MX-GP"
			(at -0.00254 -4.78536 180)
			(unlocked yes)
			(layer "F.Fab")
			(hide yes)
			(effects
				(font
					(size 1.016 1.016)
					(thickness 0.1524)
				)
			)
		)
		(property "Device Type" "C1210H107"
			(at -0.00254 -6.38048 180)
			(unlocked yes)
			(layer "F.Fab")
			(hide yes)
			(effects
				(font
					(size 1.016 1.016)
					(thickness 0.1524)
				)
			)
		)
		(duplicate_pad_numbers_are_jumpers no)
		(fp_line
			(start 1.5748 2.3368)
			(end 1.5748 0.762)
			(stroke
				(width 0.1524)
				(type default)
			)
			(layer "F.SilkS")
		)
		(fp_line
			(start 1.5748 -0.762)
			(end 1.5748 -2.3368)
			(stroke
				(width 0.1524)
				(type default)
			)
			(layer "F.SilkS")
		)
		(fp_line
			(start 1.5748 -2.3368)
			(end -1.5748 -2.3368)
			(stroke
				(width 0.1524)
				(type default)
			)
			(layer "F.SilkS")
		)
		(fp_line
			(start -1.5748 2.3368)
			(end 1.5748 2.3368)
			(stroke
				(width 0.1524)
				(type default)
			)
			(layer "F.SilkS")
		)
		(fp_line
			(start -1.5748 0.762)
			(end -1.5748 2.3368)
			(stroke
				(width 0.1524)
				(type default)
			)
			(layer "F.SilkS")
		)
		(fp_line
			(start -1.5748 -2.3368)
			(end -1.5748 -0.762)
			(stroke
				(width 0.1524)
				(type default)
			)
			(layer "F.SilkS")
		)
		(fp_rect
			(start -1.651 2.413)
			(end 1.651 -2.413)
			(stroke
				(width 0)
				(type default)
			)
			(fill no)
			(layer "F.CrtYd")
		)
		(fp_poly
			(pts
				(xy 1.651 2.413) (xy 1.651 -2.413) (xy -1.651 -2.413) (xy -1.651 2.413)
			)
			(stroke
				(width 0)
				(type default)
			)
			(fill no)
			(layer "F.Fab")
		)
		(pad "1" smd rect
			(at 0 -1.4732 180)
			(size 2.794 1.397)
			(layers "F.Cu" "F.Mask" "F.Paste")
			(net "P12V")
		)
		(pad "2" smd rect
			(at 0 1.4732 180)
			(size 2.794 1.397)
			(layers "F.Cu" "F.Mask" "F.Paste")
			(net "GND")
		)
	)
	(footprint ""
		(layer "F.Cu")
		(at 14.059408 -98.824796)
		(property "Reference" "R370"
			(at 0 0 0)
			(layer "F.SilkS")
			(hide yes)
			(effects
				(font
					(size 1.27 1.27)
				)
			)
		)
		(property "Value" "4K7R2J-2-GP"
			(at 0.064008 -3.993896 0)
			(unlocked yes)
			(layer "F.Fab")
			(hide yes)
			(effects
				(font
					(size 1.016 1.016)
					(thickness 0.1524)
				)
			)
		)
		(property "Device Type" "R402H16"
			(at 0.064008 -5.517896 0)
			(unlocked yes)
			(layer "F.Fab")
			(hide yes)
			(effects
				(font
					(size 1.016 1.016)
					(thickness 0.1524)
				)
			)
		)
		(duplicate_pad_numbers_are_jumpers no)
		(fp_line
			(start -0.508 -0.9398)
			(end -0.508 0.9398)
			(stroke
				(width 0.1524)
				(type default)
			)
			(layer "F.SilkS")
		)
		(fp_line
			(start 0.508 -0.9398)
			(end -0.508 -0.9398)
			(stroke
				(width 0.1524)
				(type default)
			)
			(layer "F.SilkS")
		)
		(fp_rect
			(start -0.508 0.9398)
			(end 0.508 -0.9398)
			(stroke
				(width 0)
				(type default)
			)
			(fill no)
			(layer "F.CrtYd")
		)
		(fp_rect
			(start -0.508 0.9398)
			(end 0.508 -0.9398)
			(stroke
				(width 0)
				(type default)
			)
			(fill no)
			(layer "F.Fab")
		)
		(pad "1" smd custom
			(at 0 -0.4445)
			(size 0.1397 0.1397)
			(layers "F.Cu" "F.Mask" "F.Paste")
			(net "P3V3")
			(options
				(clearance outline)
				(anchor circle)
			)
			(primitives
				(gr_poly
					(pts
						(arc
							(start -0.1778 -0.2794)
							(mid -0.249642 -0.249642)
							(end -0.2794 -0.1778)
						)
						(arc
							(start -0.2794 0.1778)
							(mid -0.249642 0.249642)
							(end -0.1778 0.2794)
						)
						(arc
							(start 0.1778 0.2794)
							(mid 0.249642 0.249642)
							(end 0.2794 0.1778)
						)
						(arc
							(start 0.2794 -0.1778)
							(mid 0.249642 -0.249642)
							(end 0.1778 -0.2794)
						)
					)
					(width 0)
					(fill yes)
				)
			)
		)
		(pad "2" smd custom
			(at 0 0.4445)
			(size 0.1397 0.1397)
			(layers "F.Cu" "F.Mask" "F.Paste")
			(net "I2C_C_BUF_SDAIN")
			(options
				(clearance outline)
				(anchor circle)
			)
			(primitives
				(gr_poly
					(pts
						(arc
							(start -0.1778 -0.2794)
							(mid -0.249642 -0.249642)
							(end -0.2794 -0.1778)
						)
						(arc
							(start -0.2794 0.1778)
							(mid -0.249642 0.249642)
							(end -0.1778 0.2794)
						)
						(arc
							(start 0.1778 0.2794)
							(mid 0.249642 0.249642)
							(end 0.2794 0.1778)
						)
						(arc
							(start 0.2794 -0.1778)
							(mid 0.249642 -0.249642)
							(end 0.1778 -0.2794)
						)
					)
					(width 0)
					(fill yes)
				)
			)
		)
	)
	(footprint ""
		(layer "F.Cu")
		(at 0.050038 -49.179226 180)
		(property "Reference" "C348"
			(at 0 0 180)
			(layer "F.SilkS")
			(hide yes)
			(effects
				(font
					(size 1.27 1.27)
				)
			)
		)
		(property "Value" "SC10U25V5KX-GP"
			(at -0.0762 -6.1214 180)
			(unlocked yes)
			(layer "F.Fab")
			(hide yes)
			(effects
				(font
					(size 1.016 1.016)
					(thickness 0.1524)
				)
			)
		)
		(property "Device Type" "C805H56"
			(at -0.0762 -8.1534 180)
			(unlocked yes)
			(layer "F.Fab")
			(hide yes)
			(effects
				(font
					(size 1.016 1.016)
					(thickness 0.1524)
				)
			)
		)
		(duplicate_pad_numbers_are_jumpers no)
		(fp_line
			(start 0.635 0)
			(end -0.635 0)
			(stroke
				(width 0.508)
				(type default)
			)
			(layer "F.SilkS")
		)
		(fp_rect
			(start -0.9652 1.778)
			(end 0.9652 -1.778)
			(stroke
				(width 0)
				(type default)
			)
			(fill no)
			(layer "F.CrtYd")
		)
		(fp_poly
			(pts
				(xy -0.9652 -1.778) (xy 0.9652 -1.778) (xy 0.9652 1.778) (xy -0.9652 1.778)
			)
			(stroke
				(width 0)
				(type default)
			)
			(fill no)
			(layer "F.Fab")
		)
		(pad "1" smd rect
			(at 0 -0.9652 180)
			(size 1.397 1.143)
			(layers "F.Cu" "F.Mask" "F.Paste")
			(net "P12V")
		)
		(pad "2" smd rect
			(at 0 0.9652 180)
			(size 1.397 1.143)
			(layers "F.Cu" "F.Mask" "F.Paste")
			(net "GND")
		)
	)
	(footprint ""
		(layer "F.Cu")
		(at 135.086344 -85.065108 -90)
		(property "Reference" "R366"
			(at 0 0 270)
			(layer "F.SilkS")
			(hide yes)
			(effects
				(font
					(size 1.27 1.27)
				)
			)
		)
		(property "Value" "0R2J-2-GP"
			(at 0.064008 -3.993896 270)
			(unlocked yes)
			(layer "F.Fab")
			(hide yes)
			(effects
				(font
					(size 1.016 1.016)
					(thickness 0.1524)
				)
			)
		)
		(property "Device Type" "R402H16"
			(at 0.064008 -5.517896 270)
			(unlocked yes)
			(layer "F.Fab")
			(hide yes)
			(effects
				(font
					(size 1.016 1.016)
					(thickness 0.1524)
				)
			)
		)
		(duplicate_pad_numbers_are_jumpers no)
		(fp_line
			(start -0.508 -0.9398)
			(end -0.508 0.9398)
			(stroke
				(width 0.1524)
				(type default)
			)
			(layer "F.SilkS")
		)
		(fp_line
			(start 0.508 -0.9398)
			(end -0.508 -0.9398)
			(stroke
				(width 0.1524)
				(type default)
			)
			(layer "F.SilkS")
		)
		(fp_rect
			(start -0.508 0.9398)
			(end 0.508 -0.9398)
			(stroke
				(width 0)
				(type default)
			)
			(fill no)
			(layer "F.CrtYd")
		)
		(fp_rect
			(start -0.508 0.9398)
			(end 0.508 -0.9398)
			(stroke
				(width 0)
				(type default)
			)
			(fill no)
			(layer "F.Fab")
		)
		(pad "1" smd custom
			(at 0 -0.4445 270)
			(size 0.1397 0.1397)
			(layers "F.Cu" "F.Mask" "F.Paste")
			(net "IR_SWITCH_E")
			(options
				(clearance outline)
				(anchor circle)
			)
			(primitives
				(gr_poly
					(pts
						(arc
							(start -0.1778 -0.2794)
							(mid -0.249642 -0.249642)
							(end -0.2794 -0.1778)
						)
						(arc
							(start -0.2794 0.1778)
							(mid -0.249642 0.249642)
							(end -0.1778 0.2794)
						)
						(arc
							(start 0.1778 0.2794)
							(mid 0.249642 0.249642)
							(end 0.2794 0.1778)
						)
						(arc
							(start 0.2794 -0.1778)
							(mid 0.249642 -0.249642)
							(end 0.1778 -0.2794)
						)
					)
					(width 0)
					(fill yes)
				)
			)
		)
		(pad "2" smd custom
			(at 0 0.4445 270)
			(size 0.1397 0.1397)
			(layers "F.Cu" "F.Mask" "F.Paste")
			(net "TRAY PRESENT_OUT_NET")
			(options
				(clearance outline)
				(anchor circle)
			)
			(primitives
				(gr_poly
					(pts
						(arc
							(start -0.1778 -0.2794)
							(mid -0.249642 -0.249642)
							(end -0.2794 -0.1778)
						)
						(arc
							(start -0.2794 0.1778)
							(mid -0.249642 0.249642)
							(end -0.1778 0.2794)
						)
						(arc
							(start 0.1778 0.2794)
							(mid 0.249642 0.249642)
							(end 0.2794 0.1778)
						)
						(arc
							(start 0.2794 -0.1778)
							(mid 0.249642 -0.249642)
							(end 0.1778 -0.2794)
						)
					)
					(width 0)
					(fill yes)
				)
			)
		)
	)
	(footprint ""
		(layer "F.Cu")
		(at 113.919 -47.371 180)
		(property "Reference" "C362"
			(at 0 0 180)
			(layer "F.SilkS")
			(hide yes)
			(effects
				(font
					(size 1.27 1.27)
				)
			)
		)
		(property "Value" "SC47U16V0MX-GP"
			(at -0.00254 -4.78536 180)
			(unlocked yes)
			(layer "F.Fab")
			(hide yes)
			(effects
				(font
					(size 1.016 1.016)
					(thickness 0.1524)
				)
			)
		)
		(property "Device Type" "C1210H107"
			(at -0.00254 -6.38048 180)
			(unlocked yes)
			(layer "F.Fab")
			(hide yes)
			(effects
				(font
					(size 1.016 1.016)
					(thickness 0.1524)
				)
			)
		)
		(duplicate_pad_numbers_are_jumpers no)
		(fp_line
			(start 1.5748 2.3368)
			(end 1.5748 0.762)
			(stroke
				(width 0.1524)
				(type default)
			)
			(layer "F.SilkS")
		)
		(fp_line
			(start 1.5748 -0.762)
			(end 1.5748 -2.3368)
			(stroke
				(width 0.1524)
				(type default)
			)
			(layer "F.SilkS")
		)
		(fp_line
			(start 1.5748 -2.3368)
			(end -1.5748 -2.3368)
			(stroke
				(width 0.1524)
				(type default)
			)
			(layer "F.SilkS")
		)
		(fp_line
			(start -1.5748 2.3368)
			(end 1.5748 2.3368)
			(stroke
				(width 0.1524)
				(type default)
			)
			(layer "F.SilkS")
		)
		(fp_line
			(start -1.5748 0.762)
			(end -1.5748 2.3368)
			(stroke
				(width 0.1524)
				(type default)
			)
			(layer "F.SilkS")
		)
		(fp_line
			(start -1.5748 -2.3368)
			(end -1.5748 -0.762)
			(stroke
				(width 0.1524)
				(type default)
			)
			(layer "F.SilkS")
		)
		(fp_rect
			(start -1.651 2.413)
			(end 1.651 -2.413)
			(stroke
				(width 0)
				(type default)
			)
			(fill no)
			(layer "F.CrtYd")
		)
		(fp_poly
			(pts
				(xy 1.651 2.413) (xy 1.651 -2.413) (xy -1.651 -2.413) (xy -1.651 2.413)
			)
			(stroke
				(width 0)
				(type default)
			)
			(fill no)
			(layer "F.Fab")
		)
		(pad "1" smd rect
			(at 0 -1.4732 180)
			(size 2.794 1.397)
			(layers "F.Cu" "F.Mask" "F.Paste")
			(net "P12V")
		)
		(pad "2" smd rect
			(at 0 1.4732 180)
			(size 2.794 1.397)
			(layers "F.Cu" "F.Mask" "F.Paste")
			(net "GND")
		)
	)
	(footprint ""
		(layer "F.Cu")
		(at 135.111744 -82.906108 90)
		(property "Reference" "R374"
			(at 0 0 90)
			(layer "F.SilkS")
			(hide yes)
			(effects
				(font
					(size 1.27 1.27)
				)
			)
		)
		(property "Value" "470KR2F-GP"
			(at 0.064008 -3.993896 90)
			(unlocked yes)
			(layer "F.Fab")
			(hide yes)
			(effects
				(font
					(size 1.016 1.016)
					(thickness 0.1524)
				)
			)
		)
		(property "Device Type" "R402H16"
			(at 0.064008 -5.517896 90)
			(unlocked yes)
			(layer "F.Fab")
			(hide yes)
			(effects
				(font
					(size 1.016 1.016)
					(thickness 0.1524)
				)
			)
		)
		(duplicate_pad_numbers_are_jumpers no)
		(fp_line
			(start 0.508 -0.9398)
			(end -0.508 -0.9398)
			(stroke
				(width 0.1524)
				(type default)
			)
			(layer "F.SilkS")
		)
		(fp_line
			(start -0.508 -0.9398)
			(end -0.508 0.9398)
			(stroke
				(width 0.1524)
				(type default)
			)
			(layer "F.SilkS")
		)
		(fp_rect
			(start -0.508 0.9398)
			(end 0.508 -0.9398)
			(stroke
				(width 0)
				(type default)
			)
			(fill no)
			(layer "F.CrtYd")
		)
		(fp_rect
			(start -0.508 0.9398)
			(end 0.508 -0.9398)
			(stroke
				(width 0)
				(type default)
			)
			(fill no)
			(layer "F.Fab")
		)
		(pad "1" smd custom
			(at 0 -0.4445 90)
			(size 0.1397 0.1397)
			(layers "F.Cu" "F.Mask" "F.Paste")
			(net "TRAY PRESENT_OUT_NET")
			(options
				(clearance outline)
				(anchor circle)
			)
			(primitives
				(gr_poly
					(pts
						(arc
							(start -0.1778 -0.2794)
							(mid -0.249642 -0.249642)
							(end -0.2794 -0.1778)
						)
						(arc
							(start -0.2794 0.1778)
							(mid -0.249642 0.249642)
							(end -0.1778 0.2794)
						)
						(arc
							(start 0.1778 0.2794)
							(mid 0.249642 0.249642)
							(end 0.2794 0.1778)
						)
						(arc
							(start 0.2794 -0.1778)
							(mid 0.249642 -0.249642)
							(end 0.1778 -0.2794)
						)
					)
					(width 0)
					(fill yes)
				)
			)
		)
		(pad "2" smd custom
			(at 0 0.4445 90)
			(size 0.1397 0.1397)
			(layers "F.Cu" "F.Mask" "F.Paste")
			(net "GND")
			(options
				(clearance outline)
				(anchor circle)
			)
			(primitives
				(gr_poly
					(pts
						(arc
							(start -0.1778 -0.2794)
							(mid -0.249642 -0.249642)
							(end -0.2794 -0.1778)
						)
						(arc
							(start -0.2794 0.1778)
							(mid -0.249642 0.249642)
							(end -0.1778 0.2794)
						)
						(arc
							(start 0.1778 0.2794)
							(mid 0.249642 0.249642)
							(end 0.2794 0.1778)
						)
						(arc
							(start 0.2794 -0.1778)
							(mid 0.249642 -0.249642)
							(end 0.1778 -0.2794)
						)
					)
					(width 0)
					(fill yes)
				)
			)
		)
	)
	(footprint ""
		(layer "F.Cu")
		(at 152.580086 -56.999886 90)
		(property "Reference" "CN4"
			(at 0 0 90)
			(layer "F.SilkS")
			(hide yes)
			(effects
				(font
					(size 1.27 1.27)
				)
			)
		)
		(property "Value" "FCI-CONN52-4R-GP"
			(at -28.321 -4.0132 90)
			(unlocked yes)
			(layer "F.Fab")
			(hide yes)
			(effects
				(font
					(size 1.016 1.016)
					(thickness 0.1524)
				)
			)
		)
		(property "Device Type" "51939-689LF"
			(at -28.321 -5.5372 90)
			(unlocked yes)
			(layer "F.Fab")
			(hide yes)
			(effects
				(font
					(size 1.016 1.016)
					(thickness 0.1524)
				)
			)
		)
		(duplicate_pad_numbers_are_jumpers no)
		(fp_line
			(start 26.289 -8.6106)
			(end 26.289 5.08)
			(stroke
				(width 0.1524)
				(type default)
			)
			(layer "F.SilkS")
		)
		(fp_line
			(start -26.289 -8.6106)
			(end 26.289 -8.6106)
			(stroke
				(width 0.1524)
				(type default)
			)
			(layer "F.SilkS")
		)
		(fp_line
			(start 26.289 5.08)
			(end -26.289 5.08)
			(stroke
				(width 0.1524)
				(type default)
			)
			(layer "F.SilkS")
		)
		(fp_line
			(start -26.289 5.08)
			(end -26.289 -8.6106)
			(stroke
				(width 0.1524)
				(type default)
			)
			(layer "F.SilkS")
		)
		(fp_circle
			(center 15.88008 -7.62)
			(end 15.88008 -6.5405)
			(stroke
				(width 0.3048)
				(type default)
			)
			(fill no)
			(layer "F.SilkS")
		)
		(fp_circle
			(center 13.34008 -7.62)
			(end 13.34008 -6.5405)
			(stroke
				(width 0.3048)
				(type default)
			)
			(fill no)
			(layer "F.SilkS")
		)
		(fp_circle
			(center 10.80008 -7.62)
			(end 10.80008 -6.5405)
			(stroke
				(width 0.3048)
				(type default)
			)
			(fill no)
			(layer "F.SilkS")
		)
		(fp_circle
			(center 8.26008 -7.62)
			(end 8.26008 -6.5405)
			(stroke
				(width 0.3048)
				(type default)
			)
			(fill no)
			(layer "F.SilkS")
		)
		(fp_circle
			(center 5.08 -7.62)
			(end 5.08 -6.5405)
			(stroke
				(width 0.3048)
				(type default)
			)
			(fill no)
			(layer "F.SilkS")
		)
		(fp_circle
			(center 2.54 -7.62)
			(end 2.54 -6.5405)
			(stroke
				(width 0.3048)
				(type default)
			)
			(fill no)
			(layer "F.SilkS")
		)
		(fp_circle
			(center 0 -7.62)
			(end 0 -6.5405)
			(stroke
				(width 0.3048)
				(type default)
			)
			(fill no)
			(layer "F.SilkS")
		)
		(fp_circle
			(center -2.54 -7.62)
			(end -2.54 -6.5405)
			(stroke
				(width 0.3048)
				(type default)
			)
			(fill no)
			(layer "F.SilkS")
		)
		(fp_circle
			(center -5.08 -7.62)
			(end -5.08 -6.5405)
			(stroke
				(width 0.3048)
				(type default)
			)
			(fill no)
			(layer "F.SilkS")
		)
		(fp_circle
			(center -8.26008 -7.62)
			(end -8.26008 -6.5405)
			(stroke
				(width 0.3048)
				(type default)
			)
			(fill no)
			(layer "F.SilkS")
		)
		(fp_circle
			(center -10.80008 -7.62)
			(end -10.80008 -6.5405)
			(stroke
				(width 0.3048)
				(type default)
			)
			(fill no)
			(layer "F.SilkS")
		)
		(fp_circle
			(center -13.34008 -7.62)
			(end -13.34008 -6.5405)
			(stroke
				(width 0.3048)
				(type default)
			)
			(fill no)
			(layer "F.SilkS")
		)
		(fp_circle
			(center -15.88008 -7.62)
			(end -15.88008 -6.5405)
			(stroke
				(width 0.3048)
				(type default)
			)
			(fill no)
			(layer "F.SilkS")
		)
		(fp_circle
			(center 15.88008 -5.08)
			(end 15.88008 -4.0005)
			(stroke
				(width 0.3048)
				(type default)
			)
			(fill no)
			(layer "F.SilkS")
		)
		(fp_circle
			(center 13.34008 -5.08)
			(end 13.34008 -4.0005)
			(stroke
				(width 0.3048)
				(type default)
			)
			(fill no)
			(layer "F.SilkS")
		)
		(fp_circle
			(center 10.80008 -5.08)
			(end 10.80008 -4.0005)
			(stroke
				(width 0.3048)
				(type default)
			)
			(fill no)
			(layer "F.SilkS")
		)
		(fp_circle
			(center 8.26008 -5.08)
			(end 8.26008 -4.0005)
			(stroke
				(width 0.3048)
				(type default)
			)
			(fill no)
			(layer "F.SilkS")
		)
		(fp_circle
			(center 5.08 -5.08)
			(end 5.08 -4.0005)
			(stroke
				(width 0.3048)
				(type default)
			)
			(fill no)
			(layer "F.SilkS")
		)
		(fp_circle
			(center 2.54 -5.08)
			(end 2.54 -4.0005)
			(stroke
				(width 0.3048)
				(type default)
			)
			(fill no)
			(layer "F.SilkS")
		)
		(fp_circle
			(center 0 -5.08)
			(end 0 -4.0005)
			(stroke
				(width 0.3048)
				(type default)
			)
			(fill no)
			(layer "F.SilkS")
		)
		(fp_circle
			(center -2.54 -5.08)
			(end -2.54 -4.0005)
			(stroke
				(width 0.3048)
				(type default)
			)
			(fill no)
			(layer "F.SilkS")
		)
		(fp_circle
			(center -5.08 -5.08)
			(end -5.08 -4.0005)
			(stroke
				(width 0.3048)
				(type default)
			)
			(fill no)
			(layer "F.SilkS")
		)
		(fp_circle
			(center -8.26008 -5.08)
			(end -8.26008 -4.0005)
			(stroke
				(width 0.3048)
				(type default)
			)
			(fill no)
			(layer "F.SilkS")
		)
		(fp_circle
			(center -10.80008 -5.08)
			(end -10.80008 -4.0005)
			(stroke
				(width 0.3048)
				(type default)
			)
			(fill no)
			(layer "F.SilkS")
		)
		(fp_circle
			(center -13.34008 -5.08)
			(end -13.34008 -4.0005)
			(stroke
				(width 0.3048)
				(type default)
			)
			(fill no)
			(layer "F.SilkS")
		)
		(fp_circle
			(center -15.88008 -5.08)
			(end -15.88008 -4.0005)
			(stroke
				(width 0.3048)
				(type default)
			)
			(fill no)
			(layer "F.SilkS")
		)
		(fp_circle
			(center 15.88008 -2.54)
			(end 15.88008 -1.4605)
			(stroke
				(width 0.3048)
				(type default)
			)
			(fill no)
			(layer "F.SilkS")
		)
		(fp_circle
			(center 13.34008 -2.54)
			(end 13.34008 -1.4605)
			(stroke
				(width 0.3048)
				(type default)
			)
			(fill no)
			(layer "F.SilkS")
		)
		(fp_circle
			(center 10.80008 -2.54)
			(end 10.80008 -1.4605)
			(stroke
				(width 0.3048)
				(type default)
			)
			(fill no)
			(layer "F.SilkS")
		)
		(fp_circle
			(center 8.26008 -2.54)
			(end 8.26008 -1.4605)
			(stroke
				(width 0.3048)
				(type default)
			)
			(fill no)
			(layer "F.SilkS")
		)
		(fp_circle
			(center 5.08 -2.54)
			(end 5.08 -1.4605)
			(stroke
				(width 0.3048)
				(type default)
			)
			(fill no)
			(layer "F.SilkS")
		)
		(fp_circle
			(center 2.54 -2.54)
			(end 2.54 -1.4605)
			(stroke
				(width 0.3048)
				(type default)
			)
			(fill no)
			(layer "F.SilkS")
		)
		(fp_circle
			(center 0 -2.54)
			(end 0 -1.4605)
			(stroke
				(width 0.3048)
				(type default)
			)
			(fill no)
			(layer "F.SilkS")
		)
		(fp_circle
			(center -2.54 -2.54)
			(end -2.54 -1.4605)
			(stroke
				(width 0.3048)
				(type default)
			)
			(fill no)
			(layer "F.SilkS")
		)
		(fp_circle
			(center -5.08 -2.54)
			(end -5.08 -1.4605)
			(stroke
				(width 0.3048)
				(type default)
			)
			(fill no)
			(layer "F.SilkS")
		)
		(fp_circle
			(center -8.26008 -2.54)
			(end -8.26008 -1.4605)
			(stroke
				(width 0.3048)
				(type default)
			)
			(fill no)
			(layer "F.SilkS")
		)
		(fp_circle
			(center -10.80008 -2.54)
			(end -10.80008 -1.4605)
			(stroke
				(width 0.3048)
				(type default)
			)
			(fill no)
			(layer "F.SilkS")
		)
		(fp_circle
			(center -13.34008 -2.54)
			(end -13.34008 -1.4605)
			(stroke
				(width 0.3048)
				(type default)
			)
			(fill no)
			(layer "F.SilkS")
		)
		(fp_circle
			(center -15.88008 -2.54)
			(end -15.88008 -1.4605)
			(stroke
				(width 0.3048)
				(type default)
			)
			(fill no)
			(layer "F.SilkS")
		)
		(fp_circle
			(center 15.88008 0)
			(end 15.88008 1.0795)
			(stroke
				(width 0.3048)
				(type default)
			)
			(fill no)
			(layer "F.SilkS")
		)
		(fp_circle
			(center 13.34008 0)
			(end 13.34008 1.0795)
			(stroke
				(width 0.3048)
				(type default)
			)
			(fill no)
			(layer "F.SilkS")
		)
		(fp_circle
			(center 10.80008 0)
			(end 10.80008 1.0795)
			(stroke
				(width 0.3048)
				(type default)
			)
			(fill no)
			(layer "F.SilkS")
		)
		(fp_circle
			(center 8.26008 0)
			(end 8.26008 1.0795)
			(stroke
				(width 0.3048)
				(type default)
			)
			(fill no)
			(layer "F.SilkS")
		)
		(fp_circle
			(center 5.08 0)
			(end 5.08 1.0795)
			(stroke
				(width 0.3048)
				(type default)
			)
			(fill no)
			(layer "F.SilkS")
		)
		(fp_circle
			(center 2.54 0)
			(end 2.54 1.0795)
			(stroke
				(width 0.3048)
				(type default)
			)
			(fill no)
			(layer "F.SilkS")
		)
		(fp_circle
			(center 0 0)
			(end 0 1.0795)
			(stroke
				(width 0.3048)
				(type default)
			)
			(fill no)
			(layer "F.SilkS")
		)
		(fp_circle
			(center -2.54 0)
			(end -2.54 1.0795)
			(stroke
				(width 0.3048)
				(type default)
			)
			(fill no)
			(layer "F.SilkS")
		)
		(fp_circle
			(center -5.08 0)
			(end -5.08 1.0795)
			(stroke
				(width 0.3048)
				(type default)
			)
			(fill no)
			(layer "F.SilkS")
		)
		(fp_circle
			(center -8.26008 0)
			(end -8.26008 1.0795)
			(stroke
				(width 0.3048)
				(type default)
			)
			(fill no)
			(layer "F.SilkS")
		)
		(fp_circle
			(center -10.80008 0)
			(end -10.80008 1.0795)
			(stroke
				(width 0.3048)
				(type default)
			)
			(fill no)
			(layer "F.SilkS")
		)
		(fp_circle
			(center -13.34008 0)
			(end -13.34008 1.0795)
			(stroke
				(width 0.3048)
				(type default)
			)
			(fill no)
			(layer "F.SilkS")
		)
		(fp_circle
			(center -15.88008 0)
			(end -15.88008 1.0795)
			(stroke
				(width 0.3048)
				(type default)
			)
			(fill no)
			(layer "F.SilkS")
		)
		(fp_rect
			(start -26.035 15.367)
			(end 26.035 -8.255)
			(stroke
				(width 0)
				(type default)
			)
			(fill no)
			(layer "F.CrtYd")
		)
		(fp_poly
			(pts
				(xy -26.543 15.875) (xy -26.543 -11.684) (xy 26.543 -11.684) (xy 26.543 -0.00635) (xy 26.035 -0.00635)
				(xy 26.035 -8.255) (xy -26.035 -8.255) (xy -26.035 15.367) (xy 26.035 15.367) (xy 26.035 0.00635)
				(xy 26.543 0.00635) (xy 26.543 15.875)
			)
			(stroke
				(width 0)
				(type default)
			)
			(fill no)
			(layer "F.CrtYd")
		)
		(fp_rect
			(start -26.543 15.875)
			(end 26.543 -11.684)
			(stroke
				(width 0)
				(type default)
			)
			(fill no)
			(layer "F.Fab")
		)
		(fp_text user "Slit"
			(at -1.7399 8.0645 90)
			(unlocked yes)
			(layer "F.SilkS")
			(effects
				(font
					(size 1.016 1.016)
					(thickness 0.1524)
				)
				(justify left)
			)
		)
		(pad "" np_thru_hole circle
			(at -22.225 0 90)
			(size 0.254 0.254)
			(drill 4.0132)
			(layers "*.Cu" "*.Mask")
			(clearance 2.2352)
			(thermal_gap 2.2352)
		)
		(pad "" np_thru_hole circle
			(at 22.225 0 90)
			(size 0.254 0.254)
			(drill 4.0132)
			(layers "*.Cu" "*.Mask")
			(clearance 2.2352)
			(thermal_gap 2.2352)
		)
		(pad "A1" thru_hole circle
			(at -5.08 0 90)
			(size 1.4478 1.4478)
			(drill 1.0414)
			(layers "*.Cu" "*.Mask")
			(remove_unused_layers no)
			(net "I2C_C_BUF_SDA_CONN")
			(clearance 0.1524)
			(thermal_gap 0.1524)
		)
		(pad "A2" thru_hole circle
			(at -2.54 0 90)
			(size 1.4478 1.4478)
			(drill 1.0414)
			(layers "*.Cu" "*.Mask")
			(remove_unused_layers no)
			(net "GND")
			(clearance 0.1524)
			(thermal_gap 0.1524)
		)
		(pad "A3" thru_hole circle
			(at 0 0 90)
			(size 1.4478 1.4478)
			(drill 1.0414)
			(layers "*.Cu" "*.Mask")
			(remove_unused_layers no)
			(net "I2C_C_BUF_SCL_CONN")
			(clearance 0.1524)
			(thermal_gap 0.1524)
		)
		(pad "A4" thru_hole circle
			(at 2.54 0 90)
			(size 1.4478 1.4478)
			(drill 1.0414)
			(layers "*.Cu" "*.Mask")
			(remove_unused_layers no)
			(net "GND")
			(clearance 0.1524)
			(thermal_gap 0.1524)
		)
		(pad "A5" thru_hole circle
			(at 5.08 0 90)
			(size 1.4478 1.4478)
			(drill 1.0414)
			(layers "*.Cu" "*.Mask")
			(remove_unused_layers no)
			(net "PWM_EXP_B_OUT")
			(clearance 0.1524)
			(thermal_gap 0.1524)
		)
		(pad "B1" thru_hole circle
			(at -5.08 -2.54 90)
			(size 1.4478 1.4478)
			(drill 1.0414)
			(layers "*.Cu" "*.Mask")
			(remove_unused_layers no)
			(net "GND")
			(clearance 0.1524)
			(thermal_gap 0.1524)
		)
		(pad "B2" thru_hole circle
			(at -2.54 -2.54 90)
			(size 1.4478 1.4478)
			(drill 1.0414)
			(layers "*.Cu" "*.Mask")
			(remove_unused_layers no)
			(net "PWM_EXP_A_OUT")
			(clearance 0.1524)
			(thermal_gap 0.1524)
		)
		(pad "B3" thru_hole circle
			(at 0 -2.54 90)
			(size 1.4478 1.4478)
			(drill 1.0414)
			(layers "*.Cu" "*.Mask")
			(remove_unused_layers no)
			(net "GND")
			(clearance 0.1524)
			(thermal_gap 0.1524)
		)
		(pad "B4" thru_hole circle
			(at 2.54 -2.54 90)
			(size 1.4478 1.4478)
			(drill 1.0414)
			(layers "*.Cu" "*.Mask")
			(remove_unused_layers no)
			(net "SELF_1B&2B_HB")
			(clearance 0.1524)
			(thermal_gap 0.1524)
		)
		(pad "B5" thru_hole circle
			(at 5.08 -2.54 90)
			(size 1.4478 1.4478)
			(drill 1.0414)
			(layers "*.Cu" "*.Mask")
			(remove_unused_layers no)
			(net "GND")
			(clearance 0.1524)
			(thermal_gap 0.1524)
		)
		(pad "C1" thru_hole circle
			(at -5.08 -5.08 90)
			(size 1.4478 1.4478)
			(drill 1.0414)
			(layers "*.Cu" "*.Mask")
			(remove_unused_layers no)
			(net "TPS2490_EN1")
			(clearance 0.1524)
			(thermal_gap 0.1524)
		)
		(pad "C2" thru_hole circle
			(at -2.54 -5.08 90)
			(size 1.4478 1.4478)
			(drill 1.0414)
			(layers "*.Cu" "*.Mask")
			(remove_unused_layers no)
			(net "TPS2490_EN2")
			(clearance 0.1524)
			(thermal_gap 0.1524)
		)
		(pad "C3" thru_hole circle
			(at 0 -5.08 90)
			(size 1.4478 1.4478)
			(drill 1.0414)
			(layers "*.Cu" "*.Mask")
			(remove_unused_layers no)
			(net "SELF_1A&2A_HB")
			(clearance 0.1524)
			(thermal_gap 0.1524)
		)
		(pad "C4" thru_hole circle
			(at 2.54 -5.08 90)
			(size 1.4478 1.4478)
			(drill 1.0414)
			(layers "*.Cu" "*.Mask")
			(remove_unused_layers no)
			(net "PEER_1A&2A_HB")
			(clearance 0.1524)
			(thermal_gap 0.1524)
		)
		(pad "C5" thru_hole circle
			(at 5.08 -5.08 90)
			(size 1.4478 1.4478)
			(drill 1.0414)
			(layers "*.Cu" "*.Mask")
			(remove_unused_layers no)
			(net "PEER_1B&2B_HB")
			(clearance 0.1524)
			(thermal_gap 0.1524)
		)
		(pad "D1" thru_hole circle
			(at -5.08 -7.62 90)
			(size 1.4478 1.4478)
			(drill 1.0414)
			(layers "*.Cu" "*.Mask")
			(remove_unused_layers no)
			(net "PEER_TRAY_PRESENT")
			(clearance 0.1524)
			(thermal_gap 0.1524)
		)
		(pad "D2" thru_hole circle
			(at -2.54 -7.62 90)
			(size 1.4478 1.4478)
			(drill 1.0414)
			(layers "*.Cu" "*.Mask")
			(remove_unused_layers no)
			(net "TRAY_ID")
			(clearance 0.1524)
			(thermal_gap 0.1524)
		)
		(pad "D3" thru_hole circle
			(at 0 -7.62 90)
			(size 1.4478 1.4478)
			(drill 1.0414)
			(layers "*.Cu" "*.Mask")
			(remove_unused_layers no)
			(net "FCB_HW_REV")
			(clearance 0.1524)
			(thermal_gap 0.1524)
		)
		(pad "D4" thru_hole circle
			(at 2.54 -7.62 90)
			(size 1.4478 1.4478)
			(drill 1.0414)
			(layers "*.Cu" "*.Mask")
			(remove_unused_layers no)
			(net "SD_LATCH_RELEASE")
			(clearance 0.1524)
			(thermal_gap 0.1524)
		)
		(pad "D5" thru_hole circle
			(at 5.08 -7.62 90)
			(size 1.4478 1.4478)
			(drill 1.0414)
			(layers "*.Cu" "*.Mask")
			(remove_unused_layers no)
			(net "SELF_TRAY_PRESENT")
			(clearance 0.1524)
			(thermal_gap 0.1524)
		)
		(pad "P1_1" thru_hole circle
			(at -15.88008 0 90)
			(size 1.4478 1.4478)
			(drill 1.0414)
			(layers "*.Cu" "*.Mask")
			(remove_unused_layers no)
			(net "P12V")
			(clearance 0.1524)
			(thermal_gap 0.1524)
		)
		(pad "P1_2" thru_hole circle
			(at -15.88008 -2.54 90)
			(size 1.4478 1.4478)
			(drill 1.0414)
			(layers "*.Cu" "*.Mask")
			(remove_unused_layers no)
			(net "P12V")
			(clearance 0.1524)
			(thermal_gap 0.1524)
		)
		(pad "P1_3" thru_hole circle
			(at -15.88008 -5.08 90)
			(size 1.4478 1.4478)
			(drill 1.0414)
			(layers "*.Cu" "*.Mask")
			(remove_unused_layers no)
			(net "P12V")
			(clearance 0.1524)
			(thermal_gap 0.1524)
		)
		(pad "P1_4" thru_hole circle
			(at -15.88008 -7.62 90)
			(size 1.4478 1.4478)
			(drill 1.0414)
			(layers "*.Cu" "*.Mask")
			(remove_unused_layers no)
			(net "P12V")
			(clearance 0.1524)
			(thermal_gap 0.1524)
		)
		(pad "P1_5" thru_hole circle
			(at -13.34008 0 90)
			(size 1.4478 1.4478)
			(drill 1.0414)
			(layers "*.Cu" "*.Mask")
			(remove_unused_layers no)
			(net "P12V")
			(clearance 0.1524)
			(thermal_gap 0.1524)
		)
		(pad "P1_6" thru_hole circle
			(at -13.34008 -2.54 90)
			(size 1.4478 1.4478)
			(drill 1.0414)
			(layers "*.Cu" "*.Mask")
			(remove_unused_layers no)
			(net "P12V")
			(clearance 0.1524)
			(thermal_gap 0.1524)
		)
		(pad "P1_7" thru_hole circle
			(at -13.34008 -5.08 90)
			(size 1.4478 1.4478)
			(drill 1.0414)
			(layers "*.Cu" "*.Mask")
			(remove_unused_layers no)
			(net "P12V")
			(clearance 0.1524)
			(thermal_gap 0.1524)
		)
		(pad "P1_8" thru_hole circle
			(at -13.34008 -7.62 90)
			(size 1.4478 1.4478)
			(drill 1.0414)
			(layers "*.Cu" "*.Mask")
			(remove_unused_layers no)
			(net "P12V")
			(clearance 0.1524)
			(thermal_gap 0.1524)
		)
		(pad "P2_1" thru_hole circle
			(at -10.80008 0 90)
			(size 1.4478 1.4478)
			(drill 1.0414)
			(layers "*.Cu" "*.Mask")
			(remove_unused_layers no)
			(net "P12V")
			(clearance 0.1524)
			(thermal_gap 0.1524)
		)
		(pad "P2_2" thru_hole circle
			(at -10.80008 -2.54 90)
			(size 1.4478 1.4478)
			(drill 1.0414)
			(layers "*.Cu" "*.Mask")
			(remove_unused_layers no)
			(net "P12V")
			(clearance 0.1524)
			(thermal_gap 0.1524)
		)
		(pad "P2_3" thru_hole circle
			(at -10.80008 -5.08 90)
			(size 1.4478 1.4478)
			(drill 1.0414)
			(layers "*.Cu" "*.Mask")
			(remove_unused_layers no)
			(net "P12V")
			(clearance 0.1524)
			(thermal_gap 0.1524)
		)
		(pad "P2_4" thru_hole circle
			(at -10.80008 -7.62 90)
			(size 1.4478 1.4478)
			(drill 1.0414)
			(layers "*.Cu" "*.Mask")
			(remove_unused_layers no)
			(net "P12V")
			(clearance 0.1524)
			(thermal_gap 0.1524)
		)
		(pad "P2_5" thru_hole circle
			(at -8.26008 0 90)
			(size 1.4478 1.4478)
			(drill 1.0414)
			(layers "*.Cu" "*.Mask")
			(remove_unused_layers no)
			(net "P12V")
			(clearance 0.1524)
			(thermal_gap 0.1524)
		)
		(pad "P2_6" thru_hole circle
			(at -8.26008 -2.54 90)
			(size 1.4478 1.4478)
			(drill 1.0414)
			(layers "*.Cu" "*.Mask")
			(remove_unused_layers no)
			(net "P12V")
			(clearance 0.1524)
			(thermal_gap 0.1524)
		)
		(pad "P2_7" thru_hole circle
			(at -8.26008 -5.08 90)
			(size 1.4478 1.4478)
			(drill 1.0414)
			(layers "*.Cu" "*.Mask")
			(remove_unused_layers no)
			(net "P12V")
			(clearance 0.1524)
			(thermal_gap 0.1524)
		)
		(pad "P2_8" thru_hole circle
			(at -8.26008 -7.62 90)
			(size 1.4478 1.4478)
			(drill 1.0414)
			(layers "*.Cu" "*.Mask")
			(remove_unused_layers no)
			(net "P12V")
			(clearance 0.1524)
			(thermal_gap 0.1524)
		)
		(pad "P3_1" thru_hole circle
			(at 8.26008 0 90)
			(size 1.4478 1.4478)
			(drill 1.0414)
			(layers "*.Cu" "*.Mask")
			(remove_unused_layers no)
			(net "GND")
			(clearance 0.1524)
			(thermal_gap 0.1524)
		)
		(pad "P3_2" thru_hole circle
			(at 8.26008 -2.54 90)
			(size 1.4478 1.4478)
			(drill 1.0414)
			(layers "*.Cu" "*.Mask")
			(remove_unused_layers no)
			(net "GND")
			(clearance 0.1524)
			(thermal_gap 0.1524)
		)
		(pad "P3_3" thru_hole circle
			(at 8.26008 -5.08 90)
			(size 1.4478 1.4478)
			(drill 1.0414)
			(layers "*.Cu" "*.Mask")
			(remove_unused_layers no)
			(net "GND")
			(clearance 0.1524)
			(thermal_gap 0.1524)
		)
		(pad "P3_4" thru_hole circle
			(at 8.26008 -7.62 90)
			(size 1.4478 1.4478)
			(drill 1.0414)
			(layers "*.Cu" "*.Mask")
			(remove_unused_layers no)
			(net "GND")
			(clearance 0.1524)
			(thermal_gap 0.1524)
		)
		(pad "P3_5" thru_hole circle
			(at 10.80008 0 90)
			(size 1.4478 1.4478)
			(drill 1.0414)
			(layers "*.Cu" "*.Mask")
			(remove_unused_layers no)
			(net "GND")
			(clearance 0.1524)
			(thermal_gap 0.1524)
		)
		(pad "P3_6" thru_hole circle
			(at 10.80008 -2.54 90)
			(size 1.4478 1.4478)
			(drill 1.0414)
			(layers "*.Cu" "*.Mask")
			(remove_unused_layers no)
			(net "GND")
			(clearance 0.1524)
			(thermal_gap 0.1524)
		)
		(pad "P3_7" thru_hole circle
			(at 10.80008 -5.08 90)
			(size 1.4478 1.4478)
			(drill 1.0414)
			(layers "*.Cu" "*.Mask")
			(remove_unused_layers no)
			(net "GND")
			(clearance 0.1524)
			(thermal_gap 0.1524)
		)
		(pad "P3_8" thru_hole circle
			(at 10.80008 -7.62 90)
			(size 1.4478 1.4478)
			(drill 1.0414)
			(layers "*.Cu" "*.Mask")
			(remove_unused_layers no)
			(net "GND")
			(clearance 0.1524)
			(thermal_gap 0.1524)
		)
		(pad "P4_1" thru_hole circle
			(at 13.34008 0 90)
			(size 1.4478 1.4478)
			(drill 1.0414)
			(layers "*.Cu" "*.Mask")
			(remove_unused_layers no)
			(net "GND")
			(clearance 0.1524)
			(thermal_gap 0.1524)
		)
		(pad "P4_2" thru_hole circle
			(at 13.34008 -2.54 90)
			(size 1.4478 1.4478)
			(drill 1.0414)
			(layers "*.Cu" "*.Mask")
			(remove_unused_layers no)
			(net "GND")
			(clearance 0.1524)
			(thermal_gap 0.1524)
		)
		(pad "P4_3" thru_hole circle
			(at 13.34008 -5.08 90)
			(size 1.4478 1.4478)
			(drill 1.0414)
			(layers "*.Cu" "*.Mask")
			(remove_unused_layers no)
			(net "GND")
			(clearance 0.1524)
			(thermal_gap 0.1524)
		)
		(pad "P4_4" thru_hole circle
			(at 13.34008 -7.62 90)
			(size 1.4478 1.4478)
			(drill 1.0414)
			(layers "*.Cu" "*.Mask")
			(remove_unused_layers no)
			(net "GND")
			(clearance 0.1524)
			(thermal_gap 0.1524)
		)
		(pad "P4_5" thru_hole circle
			(at 15.88008 0 90)
			(size 1.4478 1.4478)
			(drill 1.0414)
			(layers "*.Cu" "*.Mask")
			(remove_unused_layers no)
			(net "GND")
			(clearance 0.1524)
			(thermal_gap 0.1524)
		)
		(pad "P4_6" thru_hole circle
			(at 15.88008 -2.54 90)
			(size 1.4478 1.4478)
			(drill 1.0414)
			(layers "*.Cu" "*.Mask")
			(remove_unused_layers no)
			(net "GND")
			(clearance 0.1524)
			(thermal_gap 0.1524)
		)
		(pad "P4_7" thru_hole circle
			(at 15.88008 -5.08 90)
			(size 1.4478 1.4478)
			(drill 1.0414)
			(layers "*.Cu" "*.Mask")
			(remove_unused_layers no)
			(net "GND")
			(clearance 0.1524)
			(thermal_gap 0.1524)
		)
		(pad "P4_8" thru_hole circle
			(at 15.88008 -7.62 90)
			(size 1.4478 1.4478)
			(drill 1.0414)
			(layers "*.Cu" "*.Mask")
			(remove_unused_layers no)
			(net "GND")
			(clearance 0.1524)
			(thermal_gap 0.1524)
		)
		(zone
			(layers "F.Cu" "B.Cu" "In1.Cu" "In2.Cu")
			(hatch none 0.5)
			(connect_pads
				(clearance 0)
			)
			(min_thickness 0.25)
			(keepout
				(tracks not_allowed)
				(vias allowed)
				(pads allowed)
				(copperpour not_allowed)
				(footprints allowed)
			)
			(placement
				(enabled no)
				(sheetname "")
			)
			(fill
				(thermal_gap 0.5)
				(thermal_bridge_width 0.5)
				(island_removal_mode 0)
			)
			(polygon
				(pts
					(arc
						(start 152.580086 -81.536286)
						(mid 152.580086 -76.913486)
						(end 152.580086 -81.536286)
					)
				)
			)
		)
		(zone
			(layers "F.Cu" "B.Cu" "In1.Cu" "In2.Cu")
			(hatch none 0.5)
			(connect_pads
				(clearance 0)
			)
			(min_thickness 0.25)
			(keepout
				(tracks not_allowed)
				(vias allowed)
				(pads allowed)
				(copperpour not_allowed)
				(footprints allowed)
			)
			(placement
				(enabled no)
				(sheetname "")
			)
			(fill
				(thermal_gap 0.5)
				(thermal_bridge_width 0.5)
				(island_removal_mode 0)
			)
			(polygon
				(pts
					(arc
						(start 152.580086 -37.086286)
						(mid 152.580086 -32.463486)
						(end 152.580086 -37.086286)
					)
				)
			)
		)
	)
	(footprint ""
		(layer "F.Cu")
		(at 10.940288 -93.356938)
		(property "Reference" "R484"
			(at 0 0 0)
			(layer "F.SilkS")
			(hide yes)
			(effects
				(font
					(size 1.27 1.27)
				)
			)
		)
		(property "Value" "0R2J-2-GP"
			(at 0.064008 -3.993896 0)
			(unlocked yes)
			(layer "F.Fab")
			(hide yes)
			(effects
				(font
					(size 1.016 1.016)
					(thickness 0.1524)
				)
			)
		)
		(property "Device Type" "R402H16"
			(at 0.064008 -5.517896 0)
			(unlocked yes)
			(layer "F.Fab")
			(hide yes)
			(effects
				(font
					(size 1.016 1.016)
					(thickness 0.1524)
				)
			)
		)
		(duplicate_pad_numbers_are_jumpers no)
		(fp_line
			(start -0.508 -0.9398)
			(end -0.508 0.9398)
			(stroke
				(width 0.1524)
				(type default)
			)
			(layer "F.SilkS")
		)
		(fp_line
			(start 0.508 -0.9398)
			(end -0.508 -0.9398)
			(stroke
				(width 0.1524)
				(type default)
			)
			(layer "F.SilkS")
		)
		(fp_rect
			(start -0.508 0.9398)
			(end 0.508 -0.9398)
			(stroke
				(width 0)
				(type default)
			)
			(fill no)
			(layer "F.CrtYd")
		)
		(fp_rect
			(start -0.508 0.9398)
			(end 0.508 -0.9398)
			(stroke
				(width 0)
				(type default)
			)
			(fill no)
			(layer "F.Fab")
		)
		(pad "1" smd custom
			(at 0 -0.4445)
			(size 0.1397 0.1397)
			(layers "F.Cu" "F.Mask" "F.Paste")
			(net "I2C_C_SCL")
			(options
				(clearance outline)
				(anchor circle)
			)
			(primitives
				(gr_poly
					(pts
						(arc
							(start -0.1778 -0.2794)
							(mid -0.249642 -0.249642)
							(end -0.2794 -0.1778)
						)
						(arc
							(start -0.2794 0.1778)
							(mid -0.249642 0.249642)
							(end -0.1778 0.2794)
						)
						(arc
							(start 0.1778 0.2794)
							(mid 0.249642 0.249642)
							(end 0.2794 0.1778)
						)
						(arc
							(start 0.2794 -0.1778)
							(mid 0.249642 -0.249642)
							(end 0.1778 -0.2794)
						)
					)
					(width 0)
					(fill yes)
				)
			)
		)
		(pad "2" smd custom
			(at 0 0.4445)
			(size 0.1397 0.1397)
			(layers "F.Cu" "F.Mask" "F.Paste")
			(net "I2C_C_BUF_SCLOUT")
			(options
				(clearance outline)
				(anchor circle)
			)
			(primitives
				(gr_poly
					(pts
						(arc
							(start -0.1778 -0.2794)
							(mid -0.249642 -0.249642)
							(end -0.2794 -0.1778)
						)
						(arc
							(start -0.2794 0.1778)
							(mid -0.249642 0.249642)
							(end -0.1778 0.2794)
						)
						(arc
							(start 0.1778 0.2794)
							(mid 0.249642 0.249642)
							(end 0.2794 0.1778)
						)
						(arc
							(start 0.2794 -0.1778)
							(mid 0.249642 -0.249642)
							(end 0.1778 -0.2794)
						)
					)
					(width 0)
					(fill yes)
				)
			)
		)
	)
	(footprint ""
		(layer "F.Cu")
		(at 155.66009 -98.799904 90)
		(property "Reference" "Q31"
			(at 0 0 90)
			(layer "F.SilkS")
			(hide yes)
			(effects
				(font
					(size 1.27 1.27)
				)
			)
		)
		(property "Value" "SENSOR-2P-GP-U"
			(at -3.4036 1.3462 90)
			(unlocked yes)
			(layer "F.Fab")
			(hide yes)
			(effects
				(font
					(size 1.016 1.016)
					(thickness 0.1524)
				)
			)
		)
		(property "Device Type" "SNR2N4036-UH166"
			(at -3.4036 -0.1778 90)
			(unlocked yes)
			(layer "F.Fab")
			(hide yes)
			(effects
				(font
					(size 1.016 1.016)
					(thickness 0.1524)
				)
			)
		)
		(duplicate_pad_numbers_are_jumpers no)
		(fp_line
			(start 2.0574 -2.6543)
			(end -2.1844 -2.6543)
			(stroke
				(width 0.1524)
				(type default)
			)
			(layer "F.SilkS")
		)
		(fp_line
			(start -2.1844 -2.6543)
			(end -2.1844 2.6543)
			(stroke
				(width 0.1524)
				(type default)
			)
			(layer "F.SilkS")
		)
		(fp_line
			(start 2.0574 2.6543)
			(end 2.0574 -2.6543)
			(stroke
				(width 0.1524)
				(type default)
			)
			(layer "F.SilkS")
		)
		(fp_line
			(start -2.1844 2.6543)
			(end 2.0574 2.6543)
			(stroke
				(width 0.1524)
				(type default)
			)
			(layer "F.SilkS")
		)
		(fp_poly
			(pts
				(xy -1.0668 3.4036) (xy -1.0668 2.7178) (xy -1.7272 2.7178) (xy -1.7272 3.4036)
			)
			(stroke
				(width 0)
				(type default)
			)
			(fill yes)
			(layer "F.SilkS")
		)
		(fp_rect
			(start -1.8034 1.9939)
			(end 1.8034 -1.9939)
			(stroke
				(width 0)
				(type default)
			)
			(fill no)
			(layer "F.CrtYd")
		)
		(fp_poly
			(pts
				(xy -2.4384 2.7305) (xy -2.4384 -2.7305) (xy 2.3114 -2.7305) (xy 2.3114 1.98882) (xy 1.8034 1.98882)
				(xy 1.8034 -1.9939) (xy -1.8034 -1.9939) (xy -1.8034 1.9939) (xy 2.3114 1.9939) (xy 2.3114 2.7305)
			)
			(stroke
				(width 0)
				(type default)
			)
			(fill no)
			(layer "F.CrtYd")
		)
		(fp_rect
			(start -2.4384 2.7305)
			(end 2.3114 -2.7305)
			(stroke
				(width 0)
				(type default)
			)
			(fill no)
			(layer "F.Fab")
		)
		(fp_text user "E"
			(at 2.038096 -3.71729 90)
			(unlocked yes)
			(layer "F.SilkS")
			(effects
				(font
					(size 1.016 1.016)
					(thickness 0.1524)
				)
			)
		)
		(fp_text user "C"
			(at 2.038096 3.64871 90)
			(unlocked yes)
			(layer "F.SilkS")
			(effects
				(font
					(size 1.016 1.016)
					(thickness 0.1524)
				)
			)
		)
		(pad "C" smd rect
			(at -0.374904 1.455674 90)
			(size 3.0988 1.8796)
			(layers "F.Cu" "F.Mask" "F.Paste")
			(net "DETECTOR_C")
		)
		(pad "E" smd rect
			(at -0.374904 -1.455674 90)
			(size 3.0988 1.8796)
			(layers "F.Cu" "F.Mask" "F.Paste")
			(net "IR_SWITCH_E")
		)
	)
	(footprint ""
		(layer "F.Cu")
		(at 136.652 -74.93)
		(property "Reference" "R379"
			(at 0 0 0)
			(layer "F.SilkS")
			(hide yes)
			(effects
				(font
					(size 1.27 1.27)
				)
			)
		)
		(property "Value" "10KR2F-2-GP"
			(at 0.064008 -3.993896 0)
			(unlocked yes)
			(layer "F.Fab")
			(hide yes)
			(effects
				(font
					(size 1.016 1.016)
					(thickness 0.1524)
				)
			)
		)
		(property "Device Type" "R402H16"
			(at 0.064008 -5.517896 0)
			(unlocked yes)
			(layer "F.Fab")
			(hide yes)
			(effects
				(font
					(size 1.016 1.016)
					(thickness 0.1524)
				)
			)
		)
		(duplicate_pad_numbers_are_jumpers no)
		(fp_line
			(start -0.508 -0.9398)
			(end -0.508 0.9398)
			(stroke
				(width 0.1524)
				(type default)
			)
			(layer "F.SilkS")
		)
		(fp_line
			(start 0.508 -0.9398)
			(end -0.508 -0.9398)
			(stroke
				(width 0.1524)
				(type default)
			)
			(layer "F.SilkS")
		)
		(fp_rect
			(start -0.508 0.9398)
			(end 0.508 -0.9398)
			(stroke
				(width 0)
				(type default)
			)
			(fill no)
			(layer "F.CrtYd")
		)
		(fp_rect
			(start -0.508 0.9398)
			(end 0.508 -0.9398)
			(stroke
				(width 0)
				(type default)
			)
			(fill no)
			(layer "F.Fab")
		)
		(pad "1" smd custom
			(at 0 -0.4445)
			(size 0.1397 0.1397)
			(layers "F.Cu" "F.Mask" "F.Paste")
			(net "P3V3")
			(options
				(clearance outline)
				(anchor circle)
			)
			(primitives
				(gr_poly
					(pts
						(arc
							(start -0.1778 -0.2794)
							(mid -0.249642 -0.249642)
							(end -0.2794 -0.1778)
						)
						(arc
							(start -0.2794 0.1778)
							(mid -0.249642 0.249642)
							(end -0.1778 0.2794)
						)
						(arc
							(start 0.1778 0.2794)
							(mid 0.249642 0.249642)
							(end 0.2794 0.1778)
						)
						(arc
							(start 0.2794 -0.1778)
							(mid 0.249642 -0.249642)
							(end 0.1778 -0.2794)
						)
					)
					(width 0)
					(fill yes)
				)
			)
		)
		(pad "2" smd custom
			(at 0 0.4445)
			(size 0.1397 0.1397)
			(layers "F.Cu" "F.Mask" "F.Paste")
			(net "SELF_TRAY_PRESENT")
			(options
				(clearance outline)
				(anchor circle)
			)
			(primitives
				(gr_poly
					(pts
						(arc
							(start -0.1778 -0.2794)
							(mid -0.249642 -0.249642)
							(end -0.2794 -0.1778)
						)
						(arc
							(start -0.2794 0.1778)
							(mid -0.249642 0.249642)
							(end -0.1778 0.2794)
						)
						(arc
							(start 0.1778 0.2794)
							(mid 0.249642 0.249642)
							(end 0.2794 0.1778)
						)
						(arc
							(start 0.2794 -0.1778)
							(mid 0.249642 -0.249642)
							(end 0.1778 -0.2794)
						)
					)
					(width 0)
					(fill yes)
				)
			)
		)
	)
	(footprint ""
		(layer "F.Cu")
		(at 8.079232 -95.029528 90)
		(property "Reference" "R388"
			(at 0 0 90)
			(layer "F.SilkS")
			(hide yes)
			(effects
				(font
					(size 1.27 1.27)
				)
			)
		)
		(property "Value" "0R2J-2-GP"
			(at 0.064008 -3.993896 90)
			(unlocked yes)
			(layer "F.Fab")
			(hide yes)
			(effects
				(font
					(size 1.016 1.016)
					(thickness 0.1524)
				)
			)
		)
		(property "Device Type" "R402H16"
			(at 0.064008 -5.517896 90)
			(unlocked yes)
			(layer "F.Fab")
			(hide yes)
			(effects
				(font
					(size 1.016 1.016)
					(thickness 0.1524)
				)
			)
		)
		(duplicate_pad_numbers_are_jumpers no)
		(fp_line
			(start 0.508 -0.9398)
			(end -0.508 -0.9398)
			(stroke
				(width 0.1524)
				(type default)
			)
			(layer "F.SilkS")
		)
		(fp_line
			(start -0.508 -0.9398)
			(end -0.508 0.9398)
			(stroke
				(width 0.1524)
				(type default)
			)
			(layer "F.SilkS")
		)
		(fp_rect
			(start -0.508 0.9398)
			(end 0.508 -0.9398)
			(stroke
				(width 0)
				(type default)
			)
			(fill no)
			(layer "F.CrtYd")
		)
		(fp_rect
			(start -0.508 0.9398)
			(end 0.508 -0.9398)
			(stroke
				(width 0)
				(type default)
			)
			(fill no)
			(layer "F.Fab")
		)
		(pad "1" smd custom
			(at 0 -0.4445 90)
			(size 0.1397 0.1397)
			(layers "F.Cu" "F.Mask" "F.Paste")
			(net "STRADDLE_I2C_C_SDA")
			(options
				(clearance outline)
				(anchor circle)
			)
			(primitives
				(gr_poly
					(pts
						(arc
							(start -0.1778 -0.2794)
							(mid -0.249642 -0.249642)
							(end -0.2794 -0.1778)
						)
						(arc
							(start -0.2794 0.1778)
							(mid -0.249642 0.249642)
							(end -0.1778 0.2794)
						)
						(arc
							(start 0.1778 0.2794)
							(mid 0.249642 0.249642)
							(end 0.2794 0.1778)
						)
						(arc
							(start 0.2794 -0.1778)
							(mid 0.249642 -0.249642)
							(end 0.1778 -0.2794)
						)
					)
					(width 0)
					(fill yes)
				)
			)
		)
		(pad "2" smd custom
			(at 0 0.4445 90)
			(size 0.1397 0.1397)
			(layers "F.Cu" "F.Mask" "F.Paste")
			(net "I2C_C_SDA")
			(options
				(clearance outline)
				(anchor circle)
			)
			(primitives
				(gr_poly
					(pts
						(arc
							(start -0.1778 -0.2794)
							(mid -0.249642 -0.249642)
							(end -0.2794 -0.1778)
						)
						(arc
							(start -0.2794 0.1778)
							(mid -0.249642 0.249642)
							(end -0.1778 0.2794)
						)
						(arc
							(start 0.1778 0.2794)
							(mid 0.249642 0.249642)
							(end 0.2794 0.1778)
						)
						(arc
							(start 0.2794 -0.1778)
							(mid 0.249642 -0.249642)
							(end 0.1778 -0.2794)
						)
					)
					(width 0)
					(fill yes)
				)
			)
		)
	)
	(footprint ""
		(layer "F.Cu")
		(at 17.220692 -93.84538 90)
		(property "Reference" "R480"
			(at 0 0 90)
			(layer "F.SilkS")
			(hide yes)
			(effects
				(font
					(size 1.27 1.27)
				)
			)
		)
		(property "Value" "0R2J-2-GP"
			(at 0.064008 -3.993896 90)
			(unlocked yes)
			(layer "F.Fab")
			(hide yes)
			(effects
				(font
					(size 1.016 1.016)
					(thickness 0.1524)
				)
			)
		)
		(property "Device Type" "R402H16"
			(at 0.064008 -5.517896 90)
			(unlocked yes)
			(layer "F.Fab")
			(hide yes)
			(effects
				(font
					(size 1.016 1.016)
					(thickness 0.1524)
				)
			)
		)
		(duplicate_pad_numbers_are_jumpers no)
		(fp_line
			(start 0.508 -0.9398)
			(end -0.508 -0.9398)
			(stroke
				(width 0.1524)
				(type default)
			)
			(layer "F.SilkS")
		)
		(fp_line
			(start -0.508 -0.9398)
			(end -0.508 0.9398)
			(stroke
				(width 0.1524)
				(type default)
			)
			(layer "F.SilkS")
		)
		(fp_rect
			(start -0.508 0.9398)
			(end 0.508 -0.9398)
			(stroke
				(width 0)
				(type default)
			)
			(fill no)
			(layer "F.CrtYd")
		)
		(fp_rect
			(start -0.508 0.9398)
			(end 0.508 -0.9398)
			(stroke
				(width 0)
				(type default)
			)
			(fill no)
			(layer "F.Fab")
		)
		(pad "1" smd custom
			(at 0 -0.4445 90)
			(size 0.1397 0.1397)
			(layers "F.Cu" "F.Mask" "F.Paste")
			(net "I2C_C_SCL")
			(options
				(clearance outline)
				(anchor circle)
			)
			(primitives
				(gr_poly
					(pts
						(arc
							(start -0.1778 -0.2794)
							(mid -0.249642 -0.249642)
							(end -0.2794 -0.1778)
						)
						(arc
							(start -0.2794 0.1778)
							(mid -0.249642 0.249642)
							(end -0.1778 0.2794)
						)
						(arc
							(start 0.1778 0.2794)
							(mid 0.249642 0.249642)
							(end 0.2794 0.1778)
						)
						(arc
							(start 0.2794 -0.1778)
							(mid 0.249642 -0.249642)
							(end 0.1778 -0.2794)
						)
					)
					(width 0)
					(fill yes)
				)
			)
		)
		(pad "2" smd custom
			(at 0 0.4445 90)
			(size 0.1397 0.1397)
			(layers "F.Cu" "F.Mask" "F.Paste")
			(net "I2C_C_BUF_SCL")
			(options
				(clearance outline)
				(anchor circle)
			)
			(primitives
				(gr_poly
					(pts
						(arc
							(start -0.1778 -0.2794)
							(mid -0.249642 -0.249642)
							(end -0.2794 -0.1778)
						)
						(arc
							(start -0.2794 0.1778)
							(mid -0.249642 0.249642)
							(end -0.1778 0.2794)
						)
						(arc
							(start 0.1778 0.2794)
							(mid 0.249642 0.249642)
							(end 0.2794 0.1778)
						)
						(arc
							(start 0.2794 -0.1778)
							(mid 0.249642 -0.249642)
							(end 0.1778 -0.2794)
						)
					)
					(width 0)
					(fill yes)
				)
			)
		)
	)
	(footprint ""
		(layer "F.Cu")
		(at 13.38707 -89.94013 180)
		(property "Reference" "R342"
			(at 0 0 180)
			(layer "F.SilkS")
			(hide yes)
			(effects
				(font
					(size 1.27 1.27)
				)
			)
		)
		(property "Value" "10KR2F-2-GP"
			(at 0.064008 -3.993896 180)
			(unlocked yes)
			(layer "F.Fab")
			(hide yes)
			(effects
				(font
					(size 1.016 1.016)
					(thickness 0.1524)
				)
			)
		)
		(property "Device Type" "R402H16"
			(at 0.064008 -5.517896 180)
			(unlocked yes)
			(layer "F.Fab")
			(hide yes)
			(effects
				(font
					(size 1.016 1.016)
					(thickness 0.1524)
				)
			)
		)
		(duplicate_pad_numbers_are_jumpers no)
		(fp_line
			(start 0.508 -0.9398)
			(end -0.508 -0.9398)
			(stroke
				(width 0.1524)
				(type default)
			)
			(layer "F.SilkS")
		)
		(fp_line
			(start -0.508 -0.9398)
			(end -0.508 0.9398)
			(stroke
				(width 0.1524)
				(type default)
			)
			(layer "F.SilkS")
		)
		(fp_rect
			(start -0.508 0.9398)
			(end 0.508 -0.9398)
			(stroke
				(width 0)
				(type default)
			)
			(fill no)
			(layer "F.CrtYd")
		)
		(fp_rect
			(start -0.508 0.9398)
			(end 0.508 -0.9398)
			(stroke
				(width 0)
				(type default)
			)
			(fill no)
			(layer "F.Fab")
		)
		(pad "1" smd custom
			(at 0 -0.4445 180)
			(size 0.1397 0.1397)
			(layers "F.Cu" "F.Mask" "F.Paste")
			(net "P3V3")
			(options
				(clearance outline)
				(anchor circle)
			)
			(primitives
				(gr_poly
					(pts
						(arc
							(start -0.1778 -0.2794)
							(mid -0.249642 -0.249642)
							(end -0.2794 -0.1778)
						)
						(arc
							(start -0.2794 0.1778)
							(mid -0.249642 0.249642)
							(end -0.1778 0.2794)
						)
						(arc
							(start 0.1778 0.2794)
							(mid 0.249642 0.249642)
							(end 0.2794 0.1778)
						)
						(arc
							(start 0.2794 -0.1778)
							(mid 0.249642 -0.249642)
							(end 0.1778 -0.2794)
						)
					)
					(width 0)
					(fill yes)
				)
			)
		)
		(pad "2" smd custom
			(at 0 0.4445 180)
			(size 0.1397 0.1397)
			(layers "F.Cu" "F.Mask" "F.Paste")
			(net "I2C_C_BUF_SCLOUT")
			(options
				(clearance outline)
				(anchor circle)
			)
			(primitives
				(gr_poly
					(pts
						(arc
							(start -0.1778 -0.2794)
							(mid -0.249642 -0.249642)
							(end -0.2794 -0.1778)
						)
						(arc
							(start -0.2794 0.1778)
							(mid -0.249642 0.249642)
							(end -0.1778 0.2794)
						)
						(arc
							(start 0.1778 0.2794)
							(mid 0.249642 0.249642)
							(end 0.2794 0.1778)
						)
						(arc
							(start 0.2794 -0.1778)
							(mid 0.249642 -0.249642)
							(end 0.1778 -0.2794)
						)
					)
					(width 0)
					(fill yes)
				)
			)
		)
	)
	(footprint ""
		(layer "F.Cu")
		(at 135.086344 -83.972908 90)
		(property "Reference" "R365"
			(at 0 0 90)
			(layer "F.SilkS")
			(hide yes)
			(effects
				(font
					(size 1.27 1.27)
				)
			)
		)
		(property "Value" "0R2J-2-GP"
			(at 0.064008 -3.993896 90)
			(unlocked yes)
			(layer "F.Fab")
			(hide yes)
			(effects
				(font
					(size 1.016 1.016)
					(thickness 0.1524)
				)
			)
		)
		(property "Device Type" "R402H16"
			(at 0.064008 -5.517896 90)
			(unlocked yes)
			(layer "F.Fab")
			(hide yes)
			(effects
				(font
					(size 1.016 1.016)
					(thickness 0.1524)
				)
			)
		)
		(duplicate_pad_numbers_are_jumpers no)
		(fp_line
			(start 0.508 -0.9398)
			(end -0.508 -0.9398)
			(stroke
				(width 0.1524)
				(type default)
			)
			(layer "F.SilkS")
		)
		(fp_line
			(start -0.508 -0.9398)
			(end -0.508 0.9398)
			(stroke
				(width 0.1524)
				(type default)
			)
			(layer "F.SilkS")
		)
		(fp_rect
			(start -0.508 0.9398)
			(end 0.508 -0.9398)
			(stroke
				(width 0)
				(type default)
			)
			(fill no)
			(layer "F.CrtYd")
		)
		(fp_rect
			(start -0.508 0.9398)
			(end 0.508 -0.9398)
			(stroke
				(width 0)
				(type default)
			)
			(fill no)
			(layer "F.Fab")
		)
		(pad "1" smd custom
			(at 0 -0.4445 90)
			(size 0.1397 0.1397)
			(layers "F.Cu" "F.Mask" "F.Paste")
			(net "TRAY PRESENT_OUT_NET")
			(options
				(clearance outline)
				(anchor circle)
			)
			(primitives
				(gr_poly
					(pts
						(arc
							(start -0.1778 -0.2794)
							(mid -0.249642 -0.249642)
							(end -0.2794 -0.1778)
						)
						(arc
							(start -0.2794 0.1778)
							(mid -0.249642 0.249642)
							(end -0.1778 0.2794)
						)
						(arc
							(start 0.1778 0.2794)
							(mid 0.249642 0.249642)
							(end 0.2794 0.1778)
						)
						(arc
							(start 0.2794 -0.1778)
							(mid 0.249642 -0.249642)
							(end 0.1778 -0.2794)
						)
					)
					(width 0)
					(fill yes)
				)
			)
		)
		(pad "2" smd custom
			(at 0 0.4445 90)
			(size 0.1397 0.1397)
			(layers "F.Cu" "F.Mask" "F.Paste")
			(net "TRAY_MOSFET_G")
			(options
				(clearance outline)
				(anchor circle)
			)
			(primitives
				(gr_poly
					(pts
						(arc
							(start -0.1778 -0.2794)
							(mid -0.249642 -0.249642)
							(end -0.2794 -0.1778)
						)
						(arc
							(start -0.2794 0.1778)
							(mid -0.249642 0.249642)
							(end -0.1778 0.2794)
						)
						(arc
							(start 0.1778 0.2794)
							(mid 0.249642 0.249642)
							(end 0.2794 0.1778)
						)
						(arc
							(start 0.2794 -0.1778)
							(mid 0.249642 -0.249642)
							(end 0.1778 -0.2794)
						)
					)
					(width 0)
					(fill yes)
				)
			)
		)
	)
	(footprint ""
		(layer "F.Cu")
		(at 135.111744 -81.813908 90)
		(property "Reference" "R375"
			(at 0 0 90)
			(layer "F.SilkS")
			(hide yes)
			(effects
				(font
					(size 1.27 1.27)
				)
			)
		)
		(property "Value" "100R2F-L1-GP-U"
			(at 0.064008 -3.993896 90)
			(unlocked yes)
			(layer "F.Fab")
			(hide yes)
			(effects
				(font
					(size 1.016 1.016)
					(thickness 0.1524)
				)
			)
		)
		(property "Device Type" "R402H14"
			(at 0.064008 -5.517896 90)
			(unlocked yes)
			(layer "F.Fab")
			(hide yes)
			(effects
				(font
					(size 1.016 1.016)
					(thickness 0.1524)
				)
			)
		)
		(duplicate_pad_numbers_are_jumpers no)
		(fp_line
			(start 0.508 -0.9398)
			(end -0.508 -0.9398)
			(stroke
				(width 0.1524)
				(type default)
			)
			(layer "F.SilkS")
		)
		(fp_line
			(start -0.508 -0.9398)
			(end -0.508 0.9398)
			(stroke
				(width 0.1524)
				(type default)
			)
			(layer "F.SilkS")
		)
		(fp_rect
			(start -0.508 0.9398)
			(end 0.508 -0.9398)
			(stroke
				(width 0)
				(type default)
			)
			(fill no)
			(layer "F.CrtYd")
		)
		(fp_rect
			(start -0.508 0.9398)
			(end 0.508 -0.9398)
			(stroke
				(width 0)
				(type default)
			)
			(fill no)
			(layer "F.Fab")
		)
		(pad "1" smd custom
			(at 0 -0.4445 90)
			(size 0.1397 0.1397)
			(layers "F.Cu" "F.Mask" "F.Paste")
			(net "TRAY PRESENT_OUT_NET")
			(options
				(clearance outline)
				(anchor circle)
			)
			(primitives
				(gr_poly
					(pts
						(arc
							(start -0.1778 -0.2794)
							(mid -0.249642 -0.249642)
							(end -0.2794 -0.1778)
						)
						(arc
							(start -0.2794 0.1778)
							(mid -0.249642 0.249642)
							(end -0.1778 0.2794)
						)
						(arc
							(start 0.1778 0.2794)
							(mid 0.249642 0.249642)
							(end 0.2794 0.1778)
						)
						(arc
							(start 0.2794 -0.1778)
							(mid 0.249642 -0.249642)
							(end 0.1778 -0.2794)
						)
					)
					(width 0)
					(fill yes)
				)
			)
		)
		(pad "2" smd custom
			(at 0 0.4445 90)
			(size 0.1397 0.1397)
			(layers "F.Cu" "F.Mask" "F.Paste")
			(net "TRAY_PRESENT_OUT_NET_B")
			(options
				(clearance outline)
				(anchor circle)
			)
			(primitives
				(gr_poly
					(pts
						(arc
							(start -0.1778 -0.2794)
							(mid -0.249642 -0.249642)
							(end -0.2794 -0.1778)
						)
						(arc
							(start -0.2794 0.1778)
							(mid -0.249642 0.249642)
							(end -0.1778 0.2794)
						)
						(arc
							(start 0.1778 0.2794)
							(mid 0.249642 0.249642)
							(end 0.2794 0.1778)
						)
						(arc
							(start 0.2794 -0.1778)
							(mid 0.249642 -0.249642)
							(end 0.1778 -0.2794)
						)
					)
					(width 0)
					(fill yes)
				)
			)
		)
	)
	(footprint ""
		(layer "F.Cu")
		(at 10.962386 -95.39859)
		(property "Reference" "R486"
			(at 0 0 0)
			(layer "F.SilkS")
			(hide yes)
			(effects
				(font
					(size 1.27 1.27)
				)
			)
		)
		(property "Value" "0R2J-2-GP"
			(at 0.064008 -3.993896 0)
			(unlocked yes)
			(layer "F.Fab")
			(hide yes)
			(effects
				(font
					(size 1.016 1.016)
					(thickness 0.1524)
				)
			)
		)
		(property "Device Type" "R402H16"
			(at 0.064008 -5.517896 0)
			(unlocked yes)
			(layer "F.Fab")
			(hide yes)
			(effects
				(font
					(size 1.016 1.016)
					(thickness 0.1524)
				)
			)
		)
		(duplicate_pad_numbers_are_jumpers no)
		(fp_line
			(start -0.508 -0.9398)
			(end -0.508 0.9398)
			(stroke
				(width 0.1524)
				(type default)
			)
			(layer "F.SilkS")
		)
		(fp_line
			(start 0.508 -0.9398)
			(end -0.508 -0.9398)
			(stroke
				(width 0.1524)
				(type default)
			)
			(layer "F.SilkS")
		)
		(fp_rect
			(start -0.508 0.9398)
			(end 0.508 -0.9398)
			(stroke
				(width 0)
				(type default)
			)
			(fill no)
			(layer "F.CrtYd")
		)
		(fp_rect
			(start -0.508 0.9398)
			(end 0.508 -0.9398)
			(stroke
				(width 0)
				(type default)
			)
			(fill no)
			(layer "F.Fab")
		)
		(pad "1" smd custom
			(at 0 -0.4445)
			(size 0.1397 0.1397)
			(layers "F.Cu" "F.Mask" "F.Paste")
			(net "I2C_C_BUF_SDAOUT")
			(options
				(clearance outline)
				(anchor circle)
			)
			(primitives
				(gr_poly
					(pts
						(arc
							(start -0.1778 -0.2794)
							(mid -0.249642 -0.249642)
							(end -0.2794 -0.1778)
						)
						(arc
							(start -0.2794 0.1778)
							(mid -0.249642 0.249642)
							(end -0.1778 0.2794)
						)
						(arc
							(start 0.1778 0.2794)
							(mid 0.249642 0.249642)
							(end 0.2794 0.1778)
						)
						(arc
							(start 0.2794 -0.1778)
							(mid 0.249642 -0.249642)
							(end 0.1778 -0.2794)
						)
					)
					(width 0)
					(fill yes)
				)
			)
		)
		(pad "2" smd custom
			(at 0 0.4445)
			(size 0.1397 0.1397)
			(layers "F.Cu" "F.Mask" "F.Paste")
			(net "I2C_C_SDA")
			(options
				(clearance outline)
				(anchor circle)
			)
			(primitives
				(gr_poly
					(pts
						(arc
							(start -0.1778 -0.2794)
							(mid -0.249642 -0.249642)
							(end -0.2794 -0.1778)
						)
						(arc
							(start -0.2794 0.1778)
							(mid -0.249642 0.249642)
							(end -0.1778 0.2794)
						)
						(arc
							(start 0.1778 0.2794)
							(mid 0.249642 0.249642)
							(end 0.2794 0.1778)
						)
						(arc
							(start 0.2794 -0.1778)
							(mid 0.249642 -0.249642)
							(end 0.1778 -0.2794)
						)
					)
					(width 0)
					(fill yes)
				)
			)
		)
	)
	(footprint ""
		(layer "F.Cu")
		(at 161.159952 -18.999962 180)
		(property "Reference" "LED1"
			(at 0 0 180)
			(layer "F.SilkS")
			(hide yes)
			(effects
				(font
					(size 1.27 1.27)
				)
			)
		)
		(property "Value" "LED-G-203-GP"
			(at -2.6924 -1.4224 180)
			(unlocked yes)
			(layer "F.Fab")
			(hide yes)
			(effects
				(font
					(size 1.016 1.016)
					(thickness 0.1524)
				)
			)
		)
		(property "Device Type" "LED1608AKH26"
			(at -2.6924 -2.9464 180)
			(unlocked yes)
			(layer "F.Fab")
			(hide yes)
			(effects
				(font
					(size 1.016 1.016)
					(thickness 0.1524)
				)
			)
		)
		(duplicate_pad_numbers_are_jumpers no)
		(fp_line
			(start 0.7493 1.651)
			(end 0.7493 1.1811)
			(stroke
				(width 0.3302)
				(type default)
			)
			(layer "F.SilkS")
		)
		(fp_line
			(start 0.6604 1.3716)
			(end -0.6604 1.3716)
			(stroke
				(width 0.1524)
				(type default)
			)
			(layer "F.SilkS")
		)
		(fp_line
			(start 0.6604 -1.3716)
			(end 0.6604 1.3716)
			(stroke
				(width 0.1524)
				(type default)
			)
			(layer "F.SilkS")
		)
		(fp_line
			(start -0.5969 1.5494)
			(end 0.5842 1.5494)
			(stroke
				(width 0.508)
				(type default)
			)
			(layer "F.SilkS")
		)
		(fp_line
			(start -0.6604 1.3716)
			(end -0.6604 -1.3716)
			(stroke
				(width 0.1524)
				(type default)
			)
			(layer "F.SilkS")
		)
		(fp_line
			(start -0.6604 -1.3716)
			(end 0.6604 -1.3716)
			(stroke
				(width 0.1524)
				(type default)
			)
			(layer "F.SilkS")
		)
		(fp_line
			(start -0.7493 1.651)
			(end -0.7493 1.1811)
			(stroke
				(width 0.3302)
				(type default)
			)
			(layer "F.SilkS")
		)
		(fp_rect
			(start -0.6223 1.3335)
			(end 0.6223 -1.3335)
			(stroke
				(width 0)
				(type default)
			)
			(fill no)
			(layer "F.CrtYd")
		)
		(fp_rect
			(start -0.6223 1.3335)
			(end 0.6223 -1.3335)
			(stroke
				(width 0)
				(type default)
			)
			(fill no)
			(layer "F.Fab")
		)
		(pad "A" smd custom
			(at 0 -0.762 180)
			(size 0.2159 0.2159)
			(layers "F.Cu" "F.Mask" "F.Paste")
			(net "TPS2490_LED")
			(options
				(clearance outline)
				(anchor circle)
			)
			(primitives
				(gr_poly
					(pts
						(arc
							(start -0.3302 -0.4318)
							(mid -0.402042 -0.402042)
							(end -0.4318 -0.3302)
						)
						(arc
							(start -0.4318 0.3302)
							(mid -0.402042 0.402042)
							(end -0.3302 0.4318)
						)
						(arc
							(start 0.3302 0.4318)
							(mid 0.402042 0.402042)
							(end 0.4318 0.3302)
						)
						(arc
							(start 0.4318 -0.3302)
							(mid 0.402042 -0.402042)
							(end 0.3302 -0.4318)
						)
					)
					(width 0)
					(fill yes)
				)
			)
		)
		(pad "K" smd custom
			(at 0 0.762 180)
			(size 0.2159 0.2159)
			(layers "F.Cu" "F.Mask" "F.Paste")
			(net "GND")
			(options
				(clearance outline)
				(anchor circle)
			)
			(primitives
				(gr_poly
					(pts
						(arc
							(start -0.3302 -0.4318)
							(mid -0.402042 -0.402042)
							(end -0.4318 -0.3302)
						)
						(arc
							(start -0.4318 0.3302)
							(mid -0.402042 0.402042)
							(end -0.3302 0.4318)
						)
						(arc
							(start 0.3302 0.4318)
							(mid 0.402042 0.402042)
							(end 0.4318 0.3302)
						)
						(arc
							(start 0.4318 -0.3302)
							(mid 0.402042 -0.402042)
							(end 0.3302 -0.4318)
						)
					)
					(width 0)
					(fill yes)
				)
			)
		)
	)
	(footprint ""
		(layer "F.Cu")
		(at 136.152382 -67.048634 90)
		(property "Reference" "R387"
			(at 0 0 90)
			(layer "F.SilkS")
			(hide yes)
			(effects
				(font
					(size 1.27 1.27)
				)
			)
		)
		(property "Value" "0R2J-2-GP"
			(at 0.064008 -3.993896 90)
			(unlocked yes)
			(layer "F.Fab")
			(hide yes)
			(effects
				(font
					(size 1.016 1.016)
					(thickness 0.1524)
				)
			)
		)
		(property "Device Type" "R402H16"
			(at 0.064008 -5.517896 90)
			(unlocked yes)
			(layer "F.Fab")
			(hide yes)
			(effects
				(font
					(size 1.016 1.016)
					(thickness 0.1524)
				)
			)
		)
		(duplicate_pad_numbers_are_jumpers no)
		(fp_line
			(start 0.508 -0.9398)
			(end -0.508 -0.9398)
			(stroke
				(width 0.1524)
				(type default)
			)
			(layer "F.SilkS")
		)
		(fp_line
			(start -0.508 -0.9398)
			(end -0.508 0.9398)
			(stroke
				(width 0.1524)
				(type default)
			)
			(layer "F.SilkS")
		)
		(fp_rect
			(start -0.508 0.9398)
			(end 0.508 -0.9398)
			(stroke
				(width 0)
				(type default)
			)
			(fill no)
			(layer "F.CrtYd")
		)
		(fp_rect
			(start -0.508 0.9398)
			(end 0.508 -0.9398)
			(stroke
				(width 0)
				(type default)
			)
			(fill no)
			(layer "F.Fab")
		)
		(pad "1" smd custom
			(at 0 -0.4445 90)
			(size 0.1397 0.1397)
			(layers "F.Cu" "F.Mask" "F.Paste")
			(net "I2C_C_BUF_SCL")
			(options
				(clearance outline)
				(anchor circle)
			)
			(primitives
				(gr_poly
					(pts
						(arc
							(start -0.1778 -0.2794)
							(mid -0.249642 -0.249642)
							(end -0.2794 -0.1778)
						)
						(arc
							(start -0.2794 0.1778)
							(mid -0.249642 0.249642)
							(end -0.1778 0.2794)
						)
						(arc
							(start 0.1778 0.2794)
							(mid 0.249642 0.249642)
							(end 0.2794 0.1778)
						)
						(arc
							(start 0.2794 -0.1778)
							(mid 0.249642 -0.249642)
							(end 0.1778 -0.2794)
						)
					)
					(width 0)
					(fill yes)
				)
			)
		)
		(pad "2" smd custom
			(at 0 0.4445 90)
			(size 0.1397 0.1397)
			(layers "F.Cu" "F.Mask" "F.Paste")
			(net "I2C_C_BUF_SCL_CONN")
			(options
				(clearance outline)
				(anchor circle)
			)
			(primitives
				(gr_poly
					(pts
						(arc
							(start -0.1778 -0.2794)
							(mid -0.249642 -0.249642)
							(end -0.2794 -0.1778)
						)
						(arc
							(start -0.2794 0.1778)
							(mid -0.249642 0.249642)
							(end -0.1778 0.2794)
						)
						(arc
							(start 0.1778 0.2794)
							(mid 0.249642 0.249642)
							(end 0.2794 0.1778)
						)
						(arc
							(start 0.2794 -0.1778)
							(mid 0.249642 -0.249642)
							(end 0.1778 -0.2794)
						)
					)
					(width 0)
					(fill yes)
				)
			)
		)
	)
	(footprint ""
		(layer "F.Cu")
		(at 130.299206 -47.183548 180)
		(property "Reference" "TC5"
			(at 0 0 180)
			(layer "F.SilkS")
			(hide yes)
			(effects
				(font
					(size 1.27 1.27)
				)
			)
		)
		(property "Value" "ST68U16VDM-1-GP"
			(at 0 -9.6012 180)
			(unlocked yes)
			(layer "F.Fab")
			(hide yes)
			(effects
				(font
					(size 1.016 1.016)
					(thickness 0.1524)
				)
			)
		)
		(property "Device Type" "CT7343H79"
			(at 0 -11.1252 180)
			(unlocked yes)
			(layer "F.Fab")
			(hide yes)
			(effects
				(font
					(size 1.016 1.016)
					(thickness 0.1524)
				)
			)
		)
		(duplicate_pad_numbers_are_jumpers no)
		(fp_line
			(start 2.286 4.8768)
			(end -2.286 4.8768)
			(stroke
				(width 0.1524)
				(type default)
			)
			(layer "F.SilkS")
		)
		(fp_line
			(start 2.286 2.032)
			(end 2.286 4.8768)
			(stroke
				(width 0.1524)
				(type default)
			)
			(layer "F.SilkS")
		)
		(fp_line
			(start 2.286 -2.032)
			(end 2.286 -4.8768)
			(stroke
				(width 0.1524)
				(type default)
			)
			(layer "F.SilkS")
		)
		(fp_line
			(start 2.286 -4.8768)
			(end -2.286 -4.8768)
			(stroke
				(width 0.1524)
				(type default)
			)
			(layer "F.SilkS")
		)
		(fp_line
			(start 2.1082 -4.699)
			(end -2.1082 -4.699)
			(stroke
				(width 0.508)
				(type default)
			)
			(layer "F.SilkS")
		)
		(fp_line
			(start -2.286 4.8768)
			(end -2.286 2.032)
			(stroke
				(width 0.1524)
				(type default)
			)
			(layer "F.SilkS")
		)
		(fp_line
			(start -2.286 -4.8768)
			(end -2.286 -2.032)
			(stroke
				(width 0.1524)
				(type default)
			)
			(layer "F.SilkS")
		)
		(fp_rect
			(start -2.1463 3.6449)
			(end 2.1463 -3.6449)
			(stroke
				(width 0)
				(type default)
			)
			(fill no)
			(layer "F.CrtYd")
		)
		(fp_poly
			(pts
				(xy -2.54 4.953) (xy -2.54 4.2926) (xy -3.81 4.2926) (xy -3.81 -4.2926) (xy -2.54 -4.2926) (xy -2.54 -4.953)
				(xy 2.54 -4.953) (xy 2.54 -4.2926) (xy 3.81 -4.2926) (xy 3.81 -1.6256) (xy 2.1463 -1.6256) (xy 2.1463 -3.6449)
				(xy -2.1463 -3.6449) (xy -2.1463 3.6449) (xy 2.1463 3.6449) (xy 2.1463 -1.6129) (xy 3.81 -1.6129)
				(xy 3.81 4.2926) (xy 2.54 4.2926) (xy 2.54 4.953)
			)
			(stroke
				(width 0)
				(type default)
			)
			(fill no)
			(layer "F.CrtYd")
		)
		(fp_rect
			(start 2.54 4.2926)
			(end 3.81 -4.2926)
			(stroke
				(width 0)
				(type default)
			)
			(fill no)
			(layer "F.Fab")
		)
		(fp_rect
			(start -2.54 4.953)
			(end 2.54 -4.953)
			(stroke
				(width 0)
				(type default)
			)
			(fill no)
			(layer "F.Fab")
		)
		(fp_rect
			(start -3.81 4.2926)
			(end -2.54 -4.2926)
			(stroke
				(width 0)
				(type default)
			)
			(fill no)
			(layer "F.Fab")
		)
		(pad "1" smd rect
			(at 0 -3.1496 180)
			(size 2.413 2.286)
			(layers "F.Cu" "F.Mask" "F.Paste")
			(net "P12V")
		)
		(pad "2" smd rect
			(at 0 3.1496 180)
			(size 2.413 2.286)
			(layers "F.Cu" "F.Mask" "F.Paste")
			(net "GND")
		)
		(zone
			(layer "F.Cu")
			(hatch none 0.5)
			(connect_pads
				(clearance 0)
			)
			(min_thickness 0.25)
			(keepout
				(tracks allowed)
				(vias not_allowed)
				(pads allowed)
				(copperpour not_allowed)
				(footprints allowed)
			)
			(placement
				(enabled no)
				(sheetname "")
			)
			(fill
				(thermal_gap 0.5)
				(thermal_bridge_width 0.5)
				(island_removal_mode 0)
			)
			(polygon
				(pts
					(xy 128.787906 -45.494448) (xy 128.787906 -42.586148) (xy 131.810506 -42.586148) (xy 131.810506 -45.481748)
					(xy 131.810506 -45.811948) (xy 128.787906 -45.811948)
				)
			)
		)
		(zone
			(layer "F.Cu")
			(hatch none 0.5)
			(connect_pads
				(clearance 0)
			)
			(min_thickness 0.25)
			(keepout
				(tracks allowed)
				(vias not_allowed)
				(pads allowed)
				(copperpour not_allowed)
				(footprints allowed)
			)
			(placement
				(enabled no)
				(sheetname "")
			)
			(fill
				(thermal_gap 0.5)
				(thermal_bridge_width 0.5)
				(island_removal_mode 0)
			)
			(polygon
				(pts
					(xy 131.810506 -51.780948) (xy 128.787906 -51.780948) (xy 128.787906 -48.885348) (xy 128.787906 -48.555148)
					(xy 131.810506 -48.555148) (xy 131.810506 -48.885348)
				)
			)
		)
	)
	(footprint ""
		(layer "F.Cu")
		(at 7.659878 -15.499842)
		(property "Reference" "H3"
			(at 0 0 0)
			(layer "F.SilkS")
			(hide yes)
			(effects
				(font
					(size 1.27 1.27)
				)
			)
		)
		(property "Value" "HTE9B9R355-R-766"
			(at -8.9789 -1.1176 0)
			(unlocked yes)
			(layer "F.Fab")
			(hide yes)
			(effects
				(font
					(size 1.016 1.016)
					(thickness 0.1524)
				)
			)
		)
		(property "Device Type" "HTE9B9R355-R-766"
			(at -8.9789 -2.6416 0)
			(unlocked yes)
			(layer "F.Fab")
			(hide yes)
			(effects
				(font
					(size 1.016 1.016)
					(thickness 0.1524)
				)
			)
		)
		(duplicate_pad_numbers_are_jumpers no)
		(fp_poly
			(pts
				(arc
					(start -4.8133 0)
					(mid 4.8133 0)
					(end -4.8133 0)
				)
			)
			(stroke
				(width 0)
				(type default)
			)
			(fill no)
			(layer "B.CrtYd")
		)
		(fp_poly
			(pts
				(arc
					(start 0 -4.8133)
					(mid 4.8133 0)
					(end 0 4.8133)
				)
				(xy -7.9629 4.8133) (xy -7.9629 -4.8133)
			)
			(stroke
				(width 0)
				(type default)
			)
			(fill no)
			(layer "F.CrtYd")
		)
		(fp_poly
			(pts
				(arc
					(start -4.8133 0)
					(mid 4.8133 0)
					(end -4.8133 0)
				)
			)
			(stroke
				(width 0)
				(type default)
			)
			(fill no)
			(layer "B.Fab")
		)
		(fp_poly
			(pts
				(arc
					(start 0 -4.8133)
					(mid 4.8133 0)
					(end 0 4.8133)
				)
				(xy -7.9629 4.8133) (xy -7.9629 -4.8133)
			)
			(stroke
				(width 0)
				(type default)
			)
			(fill no)
			(layer "F.Fab")
		)
		(pad "1" thru_hole custom
			(at 0 0)
			(size 2.25425 2.25425)
			(drill 3.556)
			(layers "*.Cu" "*.Mask")
			(remove_unused_layers no)
			(net "GND")
			(clearance -3.7973)
			(thermal_gap 0.3048)
			(options
				(clearance outline)
				(anchor circle)
			)
			(primitives
				(gr_poly
					(pts
						(arc
							(start 1.5748 -4.5085)
							(mid 6.0833 0)
							(end 1.5748 4.5085)
						)
						(xy -6.0833 4.5085) (xy -6.0833 -4.5085)
					)
					(width 0)
					(fill yes)
				)
			)
			(padstack
				(mode front_inner_back)
				(layer "Inner"
					(shape circle)
					(size 3.9624 3.9624)
					(clearance 0.3048)
				)
				(layer "B.Cu"
					(shape circle)
					(size 9.017 9.017)
					(clearance -2.2225)
				)
			)
		)
	)
	(footprint ""
		(layer "F.Cu")
		(at 133.223 -81.788 -90)
		(property "Reference" "R482"
			(at 0 0 270)
			(layer "F.SilkS")
			(hide yes)
			(effects
				(font
					(size 1.27 1.27)
				)
			)
		)
		(property "Value" "0R2J-2-GP"
			(at 0.064008 -3.993896 270)
			(unlocked yes)
			(layer "F.Fab")
			(hide yes)
			(effects
				(font
					(size 1.016 1.016)
					(thickness 0.1524)
				)
			)
		)
		(property "Device Type" "R402H16"
			(at 0.064008 -5.517896 270)
			(unlocked yes)
			(layer "F.Fab")
			(hide yes)
			(effects
				(font
					(size 1.016 1.016)
					(thickness 0.1524)
				)
			)
		)
		(duplicate_pad_numbers_are_jumpers no)
		(fp_line
			(start -0.508 -0.9398)
			(end -0.508 0.9398)
			(stroke
				(width 0.1524)
				(type default)
			)
			(layer "F.SilkS")
		)
		(fp_line
			(start 0.508 -0.9398)
			(end -0.508 -0.9398)
			(stroke
				(width 0.1524)
				(type default)
			)
			(layer "F.SilkS")
		)
		(fp_rect
			(start -0.508 0.9398)
			(end 0.508 -0.9398)
			(stroke
				(width 0)
				(type default)
			)
			(fill no)
			(layer "F.CrtYd")
		)
		(fp_rect
			(start -0.508 0.9398)
			(end 0.508 -0.9398)
			(stroke
				(width 0)
				(type default)
			)
			(fill no)
			(layer "F.Fab")
		)
		(pad "1" smd custom
			(at 0 -0.4445 270)
			(size 0.1397 0.1397)
			(layers "F.Cu" "F.Mask" "F.Paste")
			(net "TRAY PRESENT_OUT#_C")
			(options
				(clearance outline)
				(anchor circle)
			)
			(primitives
				(gr_poly
					(pts
						(arc
							(start -0.1778 -0.2794)
							(mid -0.249642 -0.249642)
							(end -0.2794 -0.1778)
						)
						(arc
							(start -0.2794 0.1778)
							(mid -0.249642 0.249642)
							(end -0.1778 0.2794)
						)
						(arc
							(start 0.1778 0.2794)
							(mid 0.249642 0.249642)
							(end 0.2794 0.1778)
						)
						(arc
							(start 0.2794 -0.1778)
							(mid 0.249642 -0.249642)
							(end 0.1778 -0.2794)
						)
					)
					(width 0)
					(fill yes)
				)
			)
		)
		(pad "2" smd custom
			(at 0 0.4445 270)
			(size 0.1397 0.1397)
			(layers "F.Cu" "F.Mask" "F.Paste")
			(net "TRAY_MOSFET_G")
			(options
				(clearance outline)
				(anchor circle)
			)
			(primitives
				(gr_poly
					(pts
						(arc
							(start -0.1778 -0.2794)
							(mid -0.249642 -0.249642)
							(end -0.2794 -0.1778)
						)
						(arc
							(start -0.2794 0.1778)
							(mid -0.249642 0.249642)
							(end -0.1778 0.2794)
						)
						(arc
							(start 0.1778 0.2794)
							(mid 0.249642 0.249642)
							(end 0.2794 0.1778)
						)
						(arc
							(start 0.2794 -0.1778)
							(mid 0.249642 -0.249642)
							(end 0.1778 -0.2794)
						)
					)
					(width 0)
					(fill yes)
				)
			)
		)
	)
	(footprint ""
		(layer "F.Cu")
		(at 148.082 -19.939)
		(property "Reference" "R391"
			(at 0 0 0)
			(layer "F.SilkS")
			(hide yes)
			(effects
				(font
					(size 1.27 1.27)
				)
			)
		)
		(property "Value" "0R2J-2-GP"
			(at 0.064008 -3.993896 0)
			(unlocked yes)
			(layer "F.Fab")
			(hide yes)
			(effects
				(font
					(size 1.016 1.016)
					(thickness 0.1524)
				)
			)
		)
		(property "Device Type" "R402H16"
			(at 0.064008 -5.517896 0)
			(unlocked yes)
			(layer "F.Fab")
			(hide yes)
			(effects
				(font
					(size 1.016 1.016)
					(thickness 0.1524)
				)
			)
		)
		(duplicate_pad_numbers_are_jumpers no)
		(fp_line
			(start -0.508 -0.9398)
			(end -0.508 0.9398)
			(stroke
				(width 0.1524)
				(type default)
			)
			(layer "F.SilkS")
		)
		(fp_line
			(start 0.508 -0.9398)
			(end -0.508 -0.9398)
			(stroke
				(width 0.1524)
				(type default)
			)
			(layer "F.SilkS")
		)
		(fp_rect
			(start -0.508 0.9398)
			(end 0.508 -0.9398)
			(stroke
				(width 0)
				(type default)
			)
			(fill no)
			(layer "F.CrtYd")
		)
		(fp_rect
			(start -0.508 0.9398)
			(end 0.508 -0.9398)
			(stroke
				(width 0)
				(type default)
			)
			(fill no)
			(layer "F.Fab")
		)
		(pad "1" smd custom
			(at 0 -0.4445)
			(size 0.1397 0.1397)
			(layers "F.Cu" "F.Mask" "F.Paste")
			(net "TPS2490_EN1")
			(options
				(clearance outline)
				(anchor circle)
			)
			(primitives
				(gr_poly
					(pts
						(arc
							(start -0.1778 -0.2794)
							(mid -0.249642 -0.249642)
							(end -0.2794 -0.1778)
						)
						(arc
							(start -0.2794 0.1778)
							(mid -0.249642 0.249642)
							(end -0.1778 0.2794)
						)
						(arc
							(start 0.1778 0.2794)
							(mid 0.249642 0.249642)
							(end 0.2794 0.1778)
						)
						(arc
							(start 0.2794 -0.1778)
							(mid 0.249642 -0.249642)
							(end 0.1778 -0.2794)
						)
					)
					(width 0)
					(fill yes)
				)
			)
		)
		(pad "2" smd custom
			(at 0 0.4445)
			(size 0.1397 0.1397)
			(layers "F.Cu" "F.Mask" "F.Paste")
			(net "TPS2490_EN2")
			(options
				(clearance outline)
				(anchor circle)
			)
			(primitives
				(gr_poly
					(pts
						(arc
							(start -0.1778 -0.2794)
							(mid -0.249642 -0.249642)
							(end -0.2794 -0.1778)
						)
						(arc
							(start -0.2794 0.1778)
							(mid -0.249642 0.249642)
							(end -0.1778 0.2794)
						)
						(arc
							(start 0.1778 0.2794)
							(mid 0.249642 0.249642)
							(end 0.2794 0.1778)
						)
						(arc
							(start 0.2794 -0.1778)
							(mid 0.249642 -0.249642)
							(end 0.1778 -0.2794)
						)
					)
					(width 0)
					(fill yes)
				)
			)
		)
	)
	(footprint ""
		(layer "F.Cu")
		(at 12.27455 -89.9541 180)
		(property "Reference" "R343"
			(at 0 0 180)
			(layer "F.SilkS")
			(hide yes)
			(effects
				(font
					(size 1.27 1.27)
				)
			)
		)
		(property "Value" "10KR2F-2-GP"
			(at 0.064008 -3.993896 180)
			(unlocked yes)
			(layer "F.Fab")
			(hide yes)
			(effects
				(font
					(size 1.016 1.016)
					(thickness 0.1524)
				)
			)
		)
		(property "Device Type" "R402H16"
			(at 0.064008 -5.517896 180)
			(unlocked yes)
			(layer "F.Fab")
			(hide yes)
			(effects
				(font
					(size 1.016 1.016)
					(thickness 0.1524)
				)
			)
		)
		(duplicate_pad_numbers_are_jumpers no)
		(fp_line
			(start 0.508 -0.9398)
			(end -0.508 -0.9398)
			(stroke
				(width 0.1524)
				(type default)
			)
			(layer "F.SilkS")
		)
		(fp_line
			(start -0.508 -0.9398)
			(end -0.508 0.9398)
			(stroke
				(width 0.1524)
				(type default)
			)
			(layer "F.SilkS")
		)
		(fp_rect
			(start -0.508 0.9398)
			(end 0.508 -0.9398)
			(stroke
				(width 0)
				(type default)
			)
			(fill no)
			(layer "F.CrtYd")
		)
		(fp_rect
			(start -0.508 0.9398)
			(end 0.508 -0.9398)
			(stroke
				(width 0)
				(type default)
			)
			(fill no)
			(layer "F.Fab")
		)
		(pad "1" smd custom
			(at 0 -0.4445 180)
			(size 0.1397 0.1397)
			(layers "F.Cu" "F.Mask" "F.Paste")
			(net "P3V3")
			(options
				(clearance outline)
				(anchor circle)
			)
			(primitives
				(gr_poly
					(pts
						(arc
							(start -0.1778 -0.2794)
							(mid -0.249642 -0.249642)
							(end -0.2794 -0.1778)
						)
						(arc
							(start -0.2794 0.1778)
							(mid -0.249642 0.249642)
							(end -0.1778 0.2794)
						)
						(arc
							(start 0.1778 0.2794)
							(mid 0.249642 0.249642)
							(end 0.2794 0.1778)
						)
						(arc
							(start 0.2794 -0.1778)
							(mid 0.249642 -0.249642)
							(end 0.1778 -0.2794)
						)
					)
					(width 0)
					(fill yes)
				)
			)
		)
		(pad "2" smd custom
			(at 0 0.4445 180)
			(size 0.1397 0.1397)
			(layers "F.Cu" "F.Mask" "F.Paste")
			(net "I2C_C_BUF_EN")
			(options
				(clearance outline)
				(anchor circle)
			)
			(primitives
				(gr_poly
					(pts
						(arc
							(start -0.1778 -0.2794)
							(mid -0.249642 -0.249642)
							(end -0.2794 -0.1778)
						)
						(arc
							(start -0.2794 0.1778)
							(mid -0.249642 0.249642)
							(end -0.1778 0.2794)
						)
						(arc
							(start 0.1778 0.2794)
							(mid 0.249642 0.249642)
							(end 0.2794 0.1778)
						)
						(arc
							(start 0.2794 -0.1778)
							(mid 0.249642 -0.249642)
							(end 0.1778 -0.2794)
						)
					)
					(width 0)
					(fill yes)
				)
			)
		)
	)
	(footprint ""
		(layer "F.Cu")
		(at 9.679686 -92.946982)
		(property "Reference" "C358"
			(at 0 0 0)
			(layer "F.SilkS")
			(hide yes)
			(effects
				(font
					(size 1.27 1.27)
				)
			)
		)
		(property "Value" "SC220P50V3JN-GP"
			(at 0 -2.8194 0)
			(unlocked yes)
			(layer "F.Fab")
			(hide yes)
			(effects
				(font
					(size 1.016 1.016)
					(thickness 0.1524)
				)
			)
		)
		(property "Device Type" "C603H36"
			(at 0 -4.3434 0)
			(unlocked yes)
			(layer "F.Fab")
			(hide yes)
			(effects
				(font
					(size 1.016 1.016)
					(thickness 0.1524)
				)
			)
		)
		(duplicate_pad_numbers_are_jumpers no)
		(fp_line
			(start 0.508 0)
			(end -0.508 0)
			(stroke
				(width 0.2032)
				(type default)
			)
			(layer "F.SilkS")
		)
		(fp_rect
			(start -0.5842 1.3335)
			(end 0.5842 -1.3335)
			(stroke
				(width 0)
				(type default)
			)
			(fill no)
			(layer "F.CrtYd")
		)
		(fp_rect
			(start -0.5842 1.3335)
			(end 0.5842 -1.3335)
			(stroke
				(width 0)
				(type default)
			)
			(fill no)
			(layer "F.Fab")
		)
		(pad "1" smd custom
			(at 0 -0.762)
			(size 0.2159 0.2159)
			(layers "F.Cu" "F.Mask" "F.Paste")
			(net "I2C_C_SCL")
			(options
				(clearance outline)
				(anchor circle)
			)
			(primitives
				(gr_poly
					(pts
						(arc
							(start -0.3302 -0.4318)
							(mid -0.402042 -0.402042)
							(end -0.4318 -0.3302)
						)
						(arc
							(start -0.4318 0.3302)
							(mid -0.402042 0.402042)
							(end -0.3302 0.4318)
						)
						(arc
							(start 0.3302 0.4318)
							(mid 0.402042 0.402042)
							(end 0.4318 0.3302)
						)
						(arc
							(start 0.4318 -0.3302)
							(mid 0.402042 -0.402042)
							(end 0.3302 -0.4318)
						)
					)
					(width 0)
					(fill yes)
				)
			)
		)
		(pad "2" smd custom
			(at 0 0.762)
			(size 0.2159 0.2159)
			(layers "F.Cu" "F.Mask" "F.Paste")
			(net "GND")
			(options
				(clearance outline)
				(anchor circle)
			)
			(primitives
				(gr_poly
					(pts
						(arc
							(start -0.3302 -0.4318)
							(mid -0.402042 -0.402042)
							(end -0.4318 -0.3302)
						)
						(arc
							(start -0.4318 0.3302)
							(mid -0.402042 0.402042)
							(end -0.3302 0.4318)
						)
						(arc
							(start 0.3302 0.4318)
							(mid 0.402042 0.402042)
							(end 0.4318 0.3302)
						)
						(arc
							(start 0.4318 -0.3302)
							(mid 0.402042 -0.402042)
							(end 0.3302 -0.4318)
						)
					)
					(width 0)
					(fill yes)
				)
			)
		)
	)
	(footprint ""
		(layer "F.Cu")
		(at 110.49 -47.371 180)
		(property "Reference" "C363"
			(at 0 0 180)
			(layer "F.SilkS")
			(hide yes)
			(effects
				(font
					(size 1.27 1.27)
				)
			)
		)
		(property "Value" "SC47U16V0MX-GP"
			(at -0.00254 -4.78536 180)
			(unlocked yes)
			(layer "F.Fab")
			(hide yes)
			(effects
				(font
					(size 1.016 1.016)
					(thickness 0.1524)
				)
			)
		)
		(property "Device Type" "C1210H107"
			(at -0.00254 -6.38048 180)
			(unlocked yes)
			(layer "F.Fab")
			(hide yes)
			(effects
				(font
					(size 1.016 1.016)
					(thickness 0.1524)
				)
			)
		)
		(duplicate_pad_numbers_are_jumpers no)
		(fp_line
			(start 1.5748 2.3368)
			(end 1.5748 0.762)
			(stroke
				(width 0.1524)
				(type default)
			)
			(layer "F.SilkS")
		)
		(fp_line
			(start 1.5748 -0.762)
			(end 1.5748 -2.3368)
			(stroke
				(width 0.1524)
				(type default)
			)
			(layer "F.SilkS")
		)
		(fp_line
			(start 1.5748 -2.3368)
			(end -1.5748 -2.3368)
			(stroke
				(width 0.1524)
				(type default)
			)
			(layer "F.SilkS")
		)
		(fp_line
			(start -1.5748 2.3368)
			(end 1.5748 2.3368)
			(stroke
				(width 0.1524)
				(type default)
			)
			(layer "F.SilkS")
		)
		(fp_line
			(start -1.5748 0.762)
			(end -1.5748 2.3368)
			(stroke
				(width 0.1524)
				(type default)
			)
			(layer "F.SilkS")
		)
		(fp_line
			(start -1.5748 -2.3368)
			(end -1.5748 -0.762)
			(stroke
				(width 0.1524)
				(type default)
			)
			(layer "F.SilkS")
		)
		(fp_rect
			(start -1.651 2.413)
			(end 1.651 -2.413)
			(stroke
				(width 0)
				(type default)
			)
			(fill no)
			(layer "F.CrtYd")
		)
		(fp_poly
			(pts
				(xy 1.651 2.413) (xy 1.651 -2.413) (xy -1.651 -2.413) (xy -1.651 2.413)
			)
			(stroke
				(width 0)
				(type default)
			)
			(fill no)
			(layer "F.Fab")
		)
		(pad "1" smd rect
			(at 0 -1.4732 180)
			(size 2.794 1.397)
			(layers "F.Cu" "F.Mask" "F.Paste")
			(net "P12V")
		)
		(pad "2" smd rect
			(at 0 1.4732 180)
			(size 2.794 1.397)
			(layers "F.Cu" "F.Mask" "F.Paste")
			(net "GND")
		)
	)
	(footprint ""
		(layer "F.Cu")
		(at 15.253208 -98.803968)
		(property "Reference" "R353"
			(at 0 0 0)
			(layer "F.SilkS")
			(hide yes)
			(effects
				(font
					(size 1.27 1.27)
				)
			)
		)
		(property "Value" "10KR2F-2-GP"
			(at 0.064008 -3.993896 0)
			(unlocked yes)
			(layer "F.Fab")
			(hide yes)
			(effects
				(font
					(size 1.016 1.016)
					(thickness 0.1524)
				)
			)
		)
		(property "Device Type" "R402H16"
			(at 0.064008 -5.517896 0)
			(unlocked yes)
			(layer "F.Fab")
			(hide yes)
			(effects
				(font
					(size 1.016 1.016)
					(thickness 0.1524)
				)
			)
		)
		(duplicate_pad_numbers_are_jumpers no)
		(fp_line
			(start -0.508 -0.9398)
			(end -0.508 0.9398)
			(stroke
				(width 0.1524)
				(type default)
			)
			(layer "F.SilkS")
		)
		(fp_line
			(start 0.508 -0.9398)
			(end -0.508 -0.9398)
			(stroke
				(width 0.1524)
				(type default)
			)
			(layer "F.SilkS")
		)
		(fp_rect
			(start -0.508 0.9398)
			(end 0.508 -0.9398)
			(stroke
				(width 0)
				(type default)
			)
			(fill no)
			(layer "F.CrtYd")
		)
		(fp_rect
			(start -0.508 0.9398)
			(end 0.508 -0.9398)
			(stroke
				(width 0)
				(type default)
			)
			(fill no)
			(layer "F.Fab")
		)
		(pad "1" smd custom
			(at 0 -0.4445)
			(size 0.1397 0.1397)
			(layers "F.Cu" "F.Mask" "F.Paste")
			(net "P3V3")
			(options
				(clearance outline)
				(anchor circle)
			)
			(primitives
				(gr_poly
					(pts
						(arc
							(start -0.1778 -0.2794)
							(mid -0.249642 -0.249642)
							(end -0.2794 -0.1778)
						)
						(arc
							(start -0.2794 0.1778)
							(mid -0.249642 0.249642)
							(end -0.1778 0.2794)
						)
						(arc
							(start 0.1778 0.2794)
							(mid 0.249642 0.249642)
							(end 0.2794 0.1778)
						)
						(arc
							(start 0.2794 -0.1778)
							(mid 0.249642 -0.249642)
							(end 0.1778 -0.2794)
						)
					)
					(width 0)
					(fill yes)
				)
			)
		)
		(pad "2" smd custom
			(at 0 0.4445)
			(size 0.1397 0.1397)
			(layers "F.Cu" "F.Mask" "F.Paste")
			(net "I2C_C_BUF_READY")
			(options
				(clearance outline)
				(anchor circle)
			)
			(primitives
				(gr_poly
					(pts
						(arc
							(start -0.1778 -0.2794)
							(mid -0.249642 -0.249642)
							(end -0.2794 -0.1778)
						)
						(arc
							(start -0.2794 0.1778)
							(mid -0.249642 0.249642)
							(end -0.1778 0.2794)
						)
						(arc
							(start 0.1778 0.2794)
							(mid 0.249642 0.249642)
							(end 0.2794 0.1778)
						)
						(arc
							(start 0.2794 -0.1778)
							(mid 0.249642 -0.249642)
							(end 0.1778 -0.2794)
						)
					)
					(width 0)
					(fill yes)
				)
			)
		)
	)
	(footprint ""
		(layer "F.Cu")
		(at 155.650692 -103.082344)
		(property "Reference" "PR65"
			(at 0 0 0)
			(layer "F.SilkS")
			(hide yes)
			(effects
				(font
					(size 1.27 1.27)
				)
			)
		)
		(property "Value" "0R3J-0-U-GP"
			(at -0.0254 -2.5146 0)
			(unlocked yes)
			(layer "F.Fab")
			(hide yes)
			(effects
				(font
					(size 1.016 1.016)
					(thickness 0.1524)
				)
			)
		)
		(property "Device Type" "R603H22"
			(at -0.0254 -4.0386 0)
			(unlocked yes)
			(layer "F.Fab")
			(hide yes)
			(effects
				(font
					(size 1.016 1.016)
					(thickness 0.1524)
				)
			)
		)
		(duplicate_pad_numbers_are_jumpers no)
		(fp_line
			(start -0.4826 0)
			(end -0.2032 0)
			(stroke
				(width 0.2032)
				(type default)
			)
			(layer "F.SilkS")
		)
		(fp_line
			(start 0.2032 0)
			(end 0.4826 0)
			(stroke
				(width 0.2032)
				(type default)
			)
			(layer "F.SilkS")
		)
		(fp_rect
			(start -0.5842 1.3335)
			(end 0.5842 -1.3335)
			(stroke
				(width 0)
				(type default)
			)
			(fill no)
			(layer "F.CrtYd")
		)
		(fp_rect
			(start -0.5842 1.3335)
			(end 0.5842 -1.3335)
			(stroke
				(width 0)
				(type default)
			)
			(fill no)
			(layer "F.Fab")
		)
		(pad "1" smd custom
			(at 0 -0.762)
			(size 0.2159 0.2159)
			(layers "F.Cu" "F.Mask" "F.Paste")
			(net "P3V3")
			(options
				(clearance outline)
				(anchor circle)
			)
			(primitives
				(gr_poly
					(pts
						(arc
							(start -0.3302 -0.4318)
							(mid -0.402042 -0.402042)
							(end -0.4318 -0.3302)
						)
						(arc
							(start -0.4318 0.3302)
							(mid -0.402042 0.402042)
							(end -0.3302 0.4318)
						)
						(arc
							(start 0.3302 0.4318)
							(mid 0.402042 0.402042)
							(end 0.4318 0.3302)
						)
						(arc
							(start 0.4318 -0.3302)
							(mid 0.402042 -0.402042)
							(end 0.3302 -0.4318)
						)
					)
					(width 0)
					(fill yes)
				)
			)
		)
		(pad "2" smd custom
			(at 0 0.762)
			(size 0.2159 0.2159)
			(layers "F.Cu" "F.Mask" "F.Paste")
			(net "DETECTOR_C")
			(options
				(clearance outline)
				(anchor circle)
			)
			(primitives
				(gr_poly
					(pts
						(arc
							(start -0.3302 -0.4318)
							(mid -0.402042 -0.402042)
							(end -0.4318 -0.3302)
						)
						(arc
							(start -0.4318 0.3302)
							(mid -0.402042 0.402042)
							(end -0.3302 0.4318)
						)
						(arc
							(start 0.3302 0.4318)
							(mid 0.402042 0.402042)
							(end 0.4318 0.3302)
						)
						(arc
							(start 0.4318 -0.3302)
							(mid 0.402042 -0.402042)
							(end 0.3302 -0.4318)
						)
					)
					(width 0)
					(fill yes)
				)
			)
		)
	)
	(footprint ""
		(layer "F.Cu")
		(at 9.372092 -84.692744 90)
		(property "Reference" "R384"
			(at 0 0 90)
			(layer "F.SilkS")
			(hide yes)
			(effects
				(font
					(size 1.27 1.27)
				)
			)
		)
		(property "Value" "0R2J-2-GP"
			(at 0.064008 -3.993896 90)
			(unlocked yes)
			(layer "F.Fab")
			(hide yes)
			(effects
				(font
					(size 1.016 1.016)
					(thickness 0.1524)
				)
			)
		)
		(property "Device Type" "R402H16"
			(at 0.064008 -5.517896 90)
			(unlocked yes)
			(layer "F.Fab")
			(hide yes)
			(effects
				(font
					(size 1.016 1.016)
					(thickness 0.1524)
				)
			)
		)
		(duplicate_pad_numbers_are_jumpers no)
		(fp_line
			(start 0.508 -0.9398)
			(end -0.508 -0.9398)
			(stroke
				(width 0.1524)
				(type default)
			)
			(layer "F.SilkS")
		)
		(fp_line
			(start -0.508 -0.9398)
			(end -0.508 0.9398)
			(stroke
				(width 0.1524)
				(type default)
			)
			(layer "F.SilkS")
		)
		(fp_rect
			(start -0.508 0.9398)
			(end 0.508 -0.9398)
			(stroke
				(width 0)
				(type default)
			)
			(fill no)
			(layer "F.CrtYd")
		)
		(fp_rect
			(start -0.508 0.9398)
			(end 0.508 -0.9398)
			(stroke
				(width 0)
				(type default)
			)
			(fill no)
			(layer "F.Fab")
		)
		(pad "1" smd custom
			(at 0 -0.4445 90)
			(size 0.1397 0.1397)
			(layers "F.Cu" "F.Mask" "F.Paste")
			(net "PWM_EXP_A")
			(options
				(clearance outline)
				(anchor circle)
			)
			(primitives
				(gr_poly
					(pts
						(arc
							(start -0.1778 -0.2794)
							(mid -0.249642 -0.249642)
							(end -0.2794 -0.1778)
						)
						(arc
							(start -0.2794 0.1778)
							(mid -0.249642 0.249642)
							(end -0.1778 0.2794)
						)
						(arc
							(start 0.1778 0.2794)
							(mid 0.249642 0.249642)
							(end 0.2794 0.1778)
						)
						(arc
							(start 0.2794 -0.1778)
							(mid 0.249642 -0.249642)
							(end 0.1778 -0.2794)
						)
					)
					(width 0)
					(fill yes)
				)
			)
		)
		(pad "2" smd custom
			(at 0 0.4445 90)
			(size 0.1397 0.1397)
			(layers "F.Cu" "F.Mask" "F.Paste")
			(net "PWM_EXP_A_OUT")
			(options
				(clearance outline)
				(anchor circle)
			)
			(primitives
				(gr_poly
					(pts
						(arc
							(start -0.1778 -0.2794)
							(mid -0.249642 -0.249642)
							(end -0.2794 -0.1778)
						)
						(arc
							(start -0.2794 0.1778)
							(mid -0.249642 0.249642)
							(end -0.1778 0.2794)
						)
						(arc
							(start 0.1778 0.2794)
							(mid 0.249642 0.249642)
							(end 0.2794 0.1778)
						)
						(arc
							(start 0.2794 -0.1778)
							(mid 0.249642 -0.249642)
							(end 0.1778 -0.2794)
						)
					)
					(width 0)
					(fill yes)
				)
			)
		)
	)
	(footprint ""
		(layer "F.Cu")
		(at 13.650468 -94.361508)
		(property "Reference" "U51"
			(at 0 0 0)
			(layer "F.SilkS")
			(hide yes)
			(effects
				(font
					(size 1.27 1.27)
				)
			)
		)
		(property "Value" "PCA9511ADP-T-GP"
			(at 0 -13.1572 0)
			(unlocked yes)
			(layer "F.Fab")
			(hide yes)
			(effects
				(font
					(size 1.016 1.016)
					(thickness 0.1524)
				)
			)
		)
		(property "Device Type" "SSOIC8-2H44"
			(at 0 -15.1892 0)
			(unlocked yes)
			(layer "F.Fab")
			(hide yes)
			(effects
				(font
					(size 1.016 1.016)
					(thickness 0.1524)
				)
			)
		)
		(duplicate_pad_numbers_are_jumpers no)
		(fp_line
			(start -1.9304 -1.016)
			(end 1.0922 -1.016)
			(stroke
				(width 0.1524)
				(type default)
			)
			(layer "F.SilkS")
		)
		(fp_line
			(start -1.9304 1.016)
			(end -1.9304 -1.016)
			(stroke
				(width 0.1524)
				(type default)
			)
			(layer "F.SilkS")
		)
		(fp_line
			(start -1.7018 1.0414)
			(end -1.7018 2.9718)
			(stroke
				(width 0.635)
				(type default)
			)
			(layer "F.SilkS")
		)
		(fp_line
			(start -1.524 0)
			(end -1.9304 -0.4064)
			(stroke
				(width 0.1524)
				(type default)
			)
			(layer "F.SilkS")
		)
		(fp_line
			(start -1.524 0)
			(end -1.9304 0.4064)
			(stroke
				(width 0.1524)
				(type default)
			)
			(layer "F.SilkS")
		)
		(fp_line
			(start 1.0922 -1.016)
			(end 1.0922 1.016)
			(stroke
				(width 0.1524)
				(type default)
			)
			(layer "F.SilkS")
		)
		(fp_line
			(start 1.0922 1.016)
			(end -1.9304 1.016)
			(stroke
				(width 0.1524)
				(type default)
			)
			(layer "F.SilkS")
		)
		(fp_poly
			(pts
				(xy -1.1938 -1.016) (xy 1.0922 -1.016) (xy 1.0922 1.016) (xy -1.1938 1.016)
			)
			(stroke
				(width 0)
				(type default)
			)
			(fill yes)
			(layer "F.SilkS")
		)
		(fp_rect
			(start -2.0066 3.3401)
			(end 2.0066 -3.3401)
			(stroke
				(width 0)
				(type default)
			)
			(fill no)
			(layer "F.CrtYd")
		)
		(fp_poly
			(pts
				(xy -2.0066 -3.3401) (xy 2.0066 -3.3401) (xy 2.0066 3.3401) (xy -2.0066 3.3401)
			)
			(stroke
				(width 0)
				(type default)
			)
			(fill no)
			(layer "F.Fab")
		)
		(pad "1" smd rect
			(at -0.97536 2.0701)
			(size 0.4064 1.524)
			(layers "F.Cu" "F.Mask" "F.Paste")
			(net "I2C_C_BUF_EN")
		)
		(pad "2" smd rect
			(at -0.32512 2.0701)
			(size 0.4064 1.524)
			(layers "F.Cu" "F.Mask" "F.Paste")
			(net "I2C_C_BUF_SCLOUT")
		)
		(pad "3" smd rect
			(at 0.32512 2.0701)
			(size 0.4064 1.524)
			(layers "F.Cu" "F.Mask" "F.Paste")
			(net "I2C_C_BUF_SCLIN")
		)
		(pad "4" smd rect
			(at 0.97536 2.0701)
			(size 0.4064 1.524)
			(layers "F.Cu" "F.Mask" "F.Paste")
			(net "GND")
		)
		(pad "5" smd rect
			(at 0.97536 -2.0701)
			(size 0.4064 1.524)
			(layers "F.Cu" "F.Mask" "F.Paste")
			(net "I2C_C_BUF_READY")
		)
		(pad "6" smd rect
			(at 0.32512 -2.0701)
			(size 0.4064 1.524)
			(layers "F.Cu" "F.Mask" "F.Paste")
			(net "I2C_C_BUF_SDAIN")
		)
		(pad "7" smd rect
			(at -0.32512 -2.0701)
			(size 0.4064 1.524)
			(layers "F.Cu" "F.Mask" "F.Paste")
			(net "I2C_C_BUF_SDAOUT")
		)
		(pad "8" smd rect
			(at -0.97536 -2.0701)
			(size 0.4064 1.524)
			(layers "F.Cu" "F.Mask" "F.Paste")
			(net "P3V3")
		)
	)
	(footprint ""
		(layer "F.Cu")
		(at 133.223 -82.804 90)
		(property "Reference" "R376"
			(at 0 0 90)
			(layer "F.SilkS")
			(hide yes)
			(effects
				(font
					(size 1.27 1.27)
				)
			)
		)
		(property "Value" "100KR2F-L1-GP"
			(at 0.064008 -3.993896 90)
			(unlocked yes)
			(layer "F.Fab")
			(hide yes)
			(effects
				(font
					(size 1.016 1.016)
					(thickness 0.1524)
				)
			)
		)
		(property "Device Type" "R402H16"
			(at 0.064008 -5.517896 90)
			(unlocked yes)
			(layer "F.Fab")
			(hide yes)
			(effects
				(font
					(size 1.016 1.016)
					(thickness 0.1524)
				)
			)
		)
		(duplicate_pad_numbers_are_jumpers no)
		(fp_line
			(start 0.508 -0.9398)
			(end -0.508 -0.9398)
			(stroke
				(width 0.1524)
				(type default)
			)
			(layer "F.SilkS")
		)
		(fp_line
			(start -0.508 -0.9398)
			(end -0.508 0.9398)
			(stroke
				(width 0.1524)
				(type default)
			)
			(layer "F.SilkS")
		)
		(fp_rect
			(start -0.508 0.9398)
			(end 0.508 -0.9398)
			(stroke
				(width 0)
				(type default)
			)
			(fill no)
			(layer "F.CrtYd")
		)
		(fp_rect
			(start -0.508 0.9398)
			(end 0.508 -0.9398)
			(stroke
				(width 0)
				(type default)
			)
			(fill no)
			(layer "F.Fab")
		)
		(pad "1" smd custom
			(at 0 -0.4445 90)
			(size 0.1397 0.1397)
			(layers "F.Cu" "F.Mask" "F.Paste")
			(net "P3V3")
			(options
				(clearance outline)
				(anchor circle)
			)
			(primitives
				(gr_poly
					(pts
						(arc
							(start -0.1778 -0.2794)
							(mid -0.249642 -0.249642)
							(end -0.2794 -0.1778)
						)
						(arc
							(start -0.2794 0.1778)
							(mid -0.249642 0.249642)
							(end -0.1778 0.2794)
						)
						(arc
							(start 0.1778 0.2794)
							(mid 0.249642 0.249642)
							(end 0.2794 0.1778)
						)
						(arc
							(start 0.2794 -0.1778)
							(mid 0.249642 -0.249642)
							(end 0.1778 -0.2794)
						)
					)
					(width 0)
					(fill yes)
				)
			)
		)
		(pad "2" smd custom
			(at 0 0.4445 90)
			(size 0.1397 0.1397)
			(layers "F.Cu" "F.Mask" "F.Paste")
			(net "TRAY PRESENT_OUT#_C")
			(options
				(clearance outline)
				(anchor circle)
			)
			(primitives
				(gr_poly
					(pts
						(arc
							(start -0.1778 -0.2794)
							(mid -0.249642 -0.249642)
							(end -0.2794 -0.1778)
						)
						(arc
							(start -0.2794 0.1778)
							(mid -0.249642 0.249642)
							(end -0.1778 0.2794)
						)
						(arc
							(start 0.1778 0.2794)
							(mid 0.249642 0.249642)
							(end 0.2794 0.1778)
						)
						(arc
							(start 0.2794 -0.1778)
							(mid 0.249642 -0.249642)
							(end 0.1778 -0.2794)
						)
					)
					(width 0)
					(fill yes)
				)
			)
		)
	)
	(footprint ""
		(layer "F.Cu")
		(at 7.659878 -105.499916)
		(property "Reference" "H2"
			(at 0 0 0)
			(layer "F.SilkS")
			(hide yes)
			(effects
				(font
					(size 1.27 1.27)
				)
			)
		)
		(property "Value" "HTE9B9R355-R-766"
			(at -8.9789 -1.1176 0)
			(unlocked yes)
			(layer "F.Fab")
			(hide yes)
			(effects
				(font
					(size 1.016 1.016)
					(thickness 0.1524)
				)
			)
		)
		(property "Device Type" "HTE9B9R355-R-766"
			(at -8.9789 -2.6416 0)
			(unlocked yes)
			(layer "F.Fab")
			(hide yes)
			(effects
				(font
					(size 1.016 1.016)
					(thickness 0.1524)
				)
			)
		)
		(duplicate_pad_numbers_are_jumpers no)
		(fp_poly
			(pts
				(arc
					(start -4.8133 0)
					(mid 4.8133 0)
					(end -4.8133 0)
				)
			)
			(stroke
				(width 0)
				(type default)
			)
			(fill no)
			(layer "B.CrtYd")
		)
		(fp_poly
			(pts
				(arc
					(start 0 -4.8133)
					(mid 4.8133 0)
					(end 0 4.8133)
				)
				(xy -7.9629 4.8133) (xy -7.9629 -4.8133)
			)
			(stroke
				(width 0)
				(type default)
			)
			(fill no)
			(layer "F.CrtYd")
		)
		(fp_poly
			(pts
				(arc
					(start -4.8133 0)
					(mid 4.8133 0)
					(end -4.8133 0)
				)
			)
			(stroke
				(width 0)
				(type default)
			)
			(fill no)
			(layer "B.Fab")
		)
		(fp_poly
			(pts
				(arc
					(start 0 -4.8133)
					(mid 4.8133 0)
					(end 0 4.8133)
				)
				(xy -7.9629 4.8133) (xy -7.9629 -4.8133)
			)
			(stroke
				(width 0)
				(type default)
			)
			(fill no)
			(layer "F.Fab")
		)
		(pad "1" thru_hole custom
			(at 0 0)
			(size 2.25425 2.25425)
			(drill 3.556)
			(layers "*.Cu" "*.Mask")
			(remove_unused_layers no)
			(net "GND")
			(clearance -3.7973)
			(thermal_gap 0.3048)
			(options
				(clearance outline)
				(anchor circle)
			)
			(primitives
				(gr_poly
					(pts
						(arc
							(start 1.5748 -4.5085)
							(mid 6.0833 0)
							(end 1.5748 4.5085)
						)
						(xy -6.0833 4.5085) (xy -6.0833 -4.5085)
					)
					(width 0)
					(fill yes)
				)
			)
			(padstack
				(mode front_inner_back)
				(layer "Inner"
					(shape circle)
					(size 3.9624 3.9624)
					(clearance 0.3048)
				)
				(layer "B.Cu"
					(shape circle)
					(size 9.017 9.017)
					(clearance -2.2225)
				)
			)
		)
	)
	(footprint ""
		(layer "F.Cu")
		(at 155.66009 -87.700104 90)
		(property "Reference" "LED16"
			(at 0 0 90)
			(layer "F.SilkS")
			(hide yes)
			(effects
				(font
					(size 1.27 1.27)
				)
			)
		)
		(property "Value" "LED-IR-1-GP"
			(at -3.513074 -0.460502 90)
			(unlocked yes)
			(layer "F.Fab")
			(hide yes)
			(effects
				(font
					(size 1.016 1.016)
					(thickness 0.1524)
				)
			)
		)
		(property "Device Type" "LED3640AKH166"
			(at -3.513074 -1.984502 90)
			(unlocked yes)
			(layer "F.Fab")
			(hide yes)
			(effects
				(font
					(size 1.016 1.016)
					(thickness 0.1524)
				)
			)
		)
		(duplicate_pad_numbers_are_jumpers no)
		(fp_line
			(start 2.0574 -2.6543)
			(end -2.1844 -2.6543)
			(stroke
				(width 0.1524)
				(type default)
			)
			(layer "F.SilkS")
		)
		(fp_line
			(start -2.1844 -2.6543)
			(end -2.1844 2.6543)
			(stroke
				(width 0.1524)
				(type default)
			)
			(layer "F.SilkS")
		)
		(fp_line
			(start 2.0574 2.6543)
			(end 2.0574 -2.6543)
			(stroke
				(width 0.1524)
				(type default)
			)
			(layer "F.SilkS")
		)
		(fp_line
			(start -2.1844 2.6543)
			(end 2.0574 2.6543)
			(stroke
				(width 0.1524)
				(type default)
			)
			(layer "F.SilkS")
		)
		(fp_line
			(start -2.1844 2.8321)
			(end 2.0574 2.8321)
			(stroke
				(width 0.508)
				(type default)
			)
			(layer "F.SilkS")
		)
		(fp_rect
			(start -1.8034 1.9939)
			(end 1.8034 -1.9939)
			(stroke
				(width 0)
				(type default)
			)
			(fill no)
			(layer "F.CrtYd")
		)
		(fp_poly
			(pts
				(xy -2.4384 2.7305) (xy -2.4384 -2.7305) (xy 2.3114 -2.7305) (xy 2.3114 1.98882) (xy 1.8034 1.98882)
				(xy 1.8034 -1.9939) (xy -1.8034 -1.9939) (xy -1.8034 1.9939) (xy 2.3114 1.9939) (xy 2.3114 2.7305)
			)
			(stroke
				(width 0)
				(type default)
			)
			(fill no)
			(layer "F.CrtYd")
		)
		(fp_rect
			(start -2.4384 2.7305)
			(end 2.3114 -2.7305)
			(stroke
				(width 0)
				(type default)
			)
			(fill no)
			(layer "F.Fab")
		)
		(pad "A" smd rect
			(at -0.374904 -1.455674 90)
			(size 3.0988 1.8796)
			(layers "F.Cu" "F.Mask" "F.Paste")
			(net "P3V3")
		)
		(pad "K" smd rect
			(at -0.374904 1.455674 90)
			(size 3.0988 1.8796)
			(layers "F.Cu" "F.Mask" "F.Paste")
			(net "EMITTER_K")
		)
	)
	(footprint ""
		(layer "F.Cu")
		(at 136.68629 -47.187358 180)
		(property "Reference" "TC4"
			(at 0 0 180)
			(layer "F.SilkS")
			(hide yes)
			(effects
				(font
					(size 1.27 1.27)
				)
			)
		)
		(property "Value" "ST68U16VDM-1-GP"
			(at 0 -9.6012 180)
			(unlocked yes)
			(layer "F.Fab")
			(hide yes)
			(effects
				(font
					(size 1.016 1.016)
					(thickness 0.1524)
				)
			)
		)
		(property "Device Type" "CT7343H79"
			(at 0 -11.1252 180)
			(unlocked yes)
			(layer "F.Fab")
			(hide yes)
			(effects
				(font
					(size 1.016 1.016)
					(thickness 0.1524)
				)
			)
		)
		(duplicate_pad_numbers_are_jumpers no)
		(fp_line
			(start 2.286 4.8768)
			(end -2.286 4.8768)
			(stroke
				(width 0.1524)
				(type default)
			)
			(layer "F.SilkS")
		)
		(fp_line
			(start 2.286 2.032)
			(end 2.286 4.8768)
			(stroke
				(width 0.1524)
				(type default)
			)
			(layer "F.SilkS")
		)
		(fp_line
			(start 2.286 -2.032)
			(end 2.286 -4.8768)
			(stroke
				(width 0.1524)
				(type default)
			)
			(layer "F.SilkS")
		)
		(fp_line
			(start 2.286 -4.8768)
			(end -2.286 -4.8768)
			(stroke
				(width 0.1524)
				(type default)
			)
			(layer "F.SilkS")
		)
		(fp_line
			(start 2.1082 -4.699)
			(end -2.1082 -4.699)
			(stroke
				(width 0.508)
				(type default)
			)
			(layer "F.SilkS")
		)
		(fp_line
			(start -2.286 4.8768)
			(end -2.286 2.032)
			(stroke
				(width 0.1524)
				(type default)
			)
			(layer "F.SilkS")
		)
		(fp_line
			(start -2.286 -4.8768)
			(end -2.286 -2.032)
			(stroke
				(width 0.1524)
				(type default)
			)
			(layer "F.SilkS")
		)
		(fp_rect
			(start -2.1463 3.6449)
			(end 2.1463 -3.6449)
			(stroke
				(width 0)
				(type default)
			)
			(fill no)
			(layer "F.CrtYd")
		)
		(fp_poly
			(pts
				(xy -2.54 4.953) (xy -2.54 4.2926) (xy -3.81 4.2926) (xy -3.81 -4.2926) (xy -2.54 -4.2926) (xy -2.54 -4.953)
				(xy 2.54 -4.953) (xy 2.54 -4.2926) (xy 3.81 -4.2926) (xy 3.81 -1.6256) (xy 2.1463 -1.6256) (xy 2.1463 -3.6449)
				(xy -2.1463 -3.6449) (xy -2.1463 3.6449) (xy 2.1463 3.6449) (xy 2.1463 -1.6129) (xy 3.81 -1.6129)
				(xy 3.81 4.2926) (xy 2.54 4.2926) (xy 2.54 4.953)
			)
			(stroke
				(width 0)
				(type default)
			)
			(fill no)
			(layer "F.CrtYd")
		)
		(fp_rect
			(start 2.54 4.2926)
			(end 3.81 -4.2926)
			(stroke
				(width 0)
				(type default)
			)
			(fill no)
			(layer "F.Fab")
		)
		(fp_rect
			(start -2.54 4.953)
			(end 2.54 -4.953)
			(stroke
				(width 0)
				(type default)
			)
			(fill no)
			(layer "F.Fab")
		)
		(fp_rect
			(start -3.81 4.2926)
			(end -2.54 -4.2926)
			(stroke
				(width 0)
				(type default)
			)
			(fill no)
			(layer "F.Fab")
		)
		(pad "1" smd rect
			(at 0 -3.1496 180)
			(size 2.413 2.286)
			(layers "F.Cu" "F.Mask" "F.Paste")
			(net "P12V")
		)
		(pad "2" smd rect
			(at 0 3.1496 180)
			(size 2.413 2.286)
			(layers "F.Cu" "F.Mask" "F.Paste")
			(net "GND")
		)
		(zone
			(layer "F.Cu")
			(hatch none 0.5)
			(connect_pads
				(clearance 0)
			)
			(min_thickness 0.25)
			(keepout
				(tracks allowed)
				(vias not_allowed)
				(pads allowed)
				(copperpour not_allowed)
				(footprints allowed)
			)
			(placement
				(enabled no)
				(sheetname "")
			)
			(fill
				(thermal_gap 0.5)
				(thermal_bridge_width 0.5)
				(island_removal_mode 0)
			)
			(polygon
				(pts
					(xy 135.17499 -45.498258) (xy 135.17499 -42.589958) (xy 138.19759 -42.589958) (xy 138.19759 -45.485558)
					(xy 138.19759 -45.815758) (xy 135.17499 -45.815758)
				)
			)
		)
		(zone
			(layer "F.Cu")
			(hatch none 0.5)
			(connect_pads
				(clearance 0)
			)
			(min_thickness 0.25)
			(keepout
				(tracks allowed)
				(vias not_allowed)
				(pads allowed)
				(copperpour not_allowed)
				(footprints allowed)
			)
			(placement
				(enabled no)
				(sheetname "")
			)
			(fill
				(thermal_gap 0.5)
				(thermal_bridge_width 0.5)
				(island_removal_mode 0)
			)
			(polygon
				(pts
					(xy 138.19759 -51.784758) (xy 135.17499 -51.784758) (xy 135.17499 -48.889158) (xy 135.17499 -48.558958)
					(xy 138.19759 -48.558958) (xy 138.19759 -48.889158)
				)
			)
		)
	)
	(footprint ""
		(layer "F.Cu")
		(at 136.152382 -68.318634 90)
		(property "Reference" "R386"
			(at 0 0 90)
			(layer "F.SilkS")
			(hide yes)
			(effects
				(font
					(size 1.27 1.27)
				)
			)
		)
		(property "Value" "0R2J-2-GP"
			(at 0.064008 -3.993896 90)
			(unlocked yes)
			(layer "F.Fab")
			(hide yes)
			(effects
				(font
					(size 1.016 1.016)
					(thickness 0.1524)
				)
			)
		)
		(property "Device Type" "R402H16"
			(at 0.064008 -5.517896 90)
			(unlocked yes)
			(layer "F.Fab")
			(hide yes)
			(effects
				(font
					(size 1.016 1.016)
					(thickness 0.1524)
				)
			)
		)
		(duplicate_pad_numbers_are_jumpers no)
		(fp_line
			(start 0.508 -0.9398)
			(end -0.508 -0.9398)
			(stroke
				(width 0.1524)
				(type default)
			)
			(layer "F.SilkS")
		)
		(fp_line
			(start -0.508 -0.9398)
			(end -0.508 0.9398)
			(stroke
				(width 0.1524)
				(type default)
			)
			(layer "F.SilkS")
		)
		(fp_rect
			(start -0.508 0.9398)
			(end 0.508 -0.9398)
			(stroke
				(width 0)
				(type default)
			)
			(fill no)
			(layer "F.CrtYd")
		)
		(fp_rect
			(start -0.508 0.9398)
			(end 0.508 -0.9398)
			(stroke
				(width 0)
				(type default)
			)
			(fill no)
			(layer "F.Fab")
		)
		(pad "1" smd custom
			(at 0 -0.4445 90)
			(size 0.1397 0.1397)
			(layers "F.Cu" "F.Mask" "F.Paste")
			(net "I2C_C_BUF_SDA")
			(options
				(clearance outline)
				(anchor circle)
			)
			(primitives
				(gr_poly
					(pts
						(arc
							(start -0.1778 -0.2794)
							(mid -0.249642 -0.249642)
							(end -0.2794 -0.1778)
						)
						(arc
							(start -0.2794 0.1778)
							(mid -0.249642 0.249642)
							(end -0.1778 0.2794)
						)
						(arc
							(start 0.1778 0.2794)
							(mid 0.249642 0.249642)
							(end 0.2794 0.1778)
						)
						(arc
							(start 0.2794 -0.1778)
							(mid 0.249642 -0.249642)
							(end 0.1778 -0.2794)
						)
					)
					(width 0)
					(fill yes)
				)
			)
		)
		(pad "2" smd custom
			(at 0 0.4445 90)
			(size 0.1397 0.1397)
			(layers "F.Cu" "F.Mask" "F.Paste")
			(net "I2C_C_BUF_SDA_CONN")
			(options
				(clearance outline)
				(anchor circle)
			)
			(primitives
				(gr_poly
					(pts
						(arc
							(start -0.1778 -0.2794)
							(mid -0.249642 -0.249642)
							(end -0.2794 -0.1778)
						)
						(arc
							(start -0.2794 0.1778)
							(mid -0.249642 0.249642)
							(end -0.1778 0.2794)
						)
						(arc
							(start 0.1778 0.2794)
							(mid 0.249642 0.249642)
							(end 0.2794 0.1778)
						)
						(arc
							(start 0.2794 -0.1778)
							(mid 0.249642 -0.249642)
							(end 0.1778 -0.2794)
						)
					)
					(width 0)
					(fill yes)
				)
			)
		)
	)
	(gr_line
		(start -10.999978 -91.45016)
		(end -9.500108 -92.95003)
		(stroke
			(width 1.524)
			(type default)
		)
		(layer "In1.Cu")
	)
	(gr_line
		(start -10.999978 -76.379832)
		(end -10.999978 -91.45016)
		(stroke
			(width 5.08)
			(type default)
		)
		(layer "In1.Cu")
	)
	(gr_line
		(start -10.999978 -72.680068)
		(end -9.500108 -74.179938)
		(stroke
			(width 1.524)
			(type default)
		)
		(layer "In1.Cu")
	)
	(gr_line
		(start -10.999978 -29.669994)
		(end -10.999978 -72.680068)
		(stroke
			(width 5.08)
			(type default)
		)
		(layer "In1.Cu")
	)
	(gr_line
		(start -9.500108 -92.95003)
		(end -0.999998 -92.95003)
		(stroke
			(width 1.524)
			(type default)
		)
		(layer "In1.Cu")
	)
	(gr_line
		(start -9.500108 -74.879962)
		(end -10.999978 -76.379832)
		(stroke
			(width 1.524)
			(type default)
		)
		(layer "In1.Cu")
	)
	(gr_line
		(start -9.500108 -74.179938)
		(end -0.350012 -74.179938)
		(stroke
			(width 1.524)
			(type default)
		)
		(layer "In1.Cu")
	)
	(gr_line
		(start -9.500108 -28.170124)
		(end -10.999978 -29.669994)
		(stroke
			(width 1.524)
			(type default)
		)
		(layer "In1.Cu")
	)
	(gr_line
		(start -8.790178 -49.13376)
		(end 104.267 -49.149)
		(stroke
			(width 0.508)
			(type default)
		)
		(layer "In1.Cu")
	)
	(gr_line
		(start -0.999998 -28.170124)
		(end -9.500108 -28.170124)
		(stroke
			(width 1.524)
			(type default)
		)
		(layer "In1.Cu")
	)
	(gr_arc
		(start -0.999998 -28.170124)
		(mid -0.292893 -27.877231)
		(end 0 -27.170126)
		(stroke
			(width 1.524)
			(type default)
		)
		(layer "In1.Cu")
	)
	(gr_line
		(start -0.350012 -74.879962)
		(end -9.500108 -74.879962)
		(stroke
			(width 1.524)
			(type default)
		)
		(layer "In1.Cu")
	)
	(gr_arc
		(start -0.350012 -74.879962)
		(mid 0 -74.52995)
		(end -0.350012 -74.179938)
		(stroke
			(width 1.524)
			(type default)
		)
		(layer "In1.Cu")
	)
	(gr_arc
		(start 0 -119.000016)
		(mid 0.292893 -119.707121)
		(end 0.999998 -120.000014)
		(stroke
			(width 1.524)
			(type default)
		)
		(layer "In1.Cu")
	)
	(gr_arc
		(start 0 -93.950028)
		(mid -0.292893 -93.242923)
		(end -0.999998 -92.95003)
		(stroke
			(width 1.524)
			(type default)
		)
		(layer "In1.Cu")
	)
	(gr_line
		(start 0 -93.950028)
		(end 0 -119.000016)
		(stroke
			(width 1.524)
			(type default)
		)
		(layer "In1.Cu")
	)
	(gr_line
		(start 0 -0.999998)
		(end 0 -27.170126)
		(stroke
			(width 1.524)
			(type default)
		)
		(layer "In1.Cu")
	)
	(gr_line
		(start 0.999998 -120.000014)
		(end 161.660078 -120.000014)
		(stroke
			(width 1.524)
			(type default)
		)
		(layer "In1.Cu")
	)
	(gr_arc
		(start 0.999998 0)
		(mid 0.292893 -0.292893)
		(end 0 -0.999998)
		(stroke
			(width 1.524)
			(type default)
		)
		(layer "In1.Cu")
	)
	(gr_line
		(start 9.779 -20.447)
		(end 0.254 -20.447)
		(stroke
			(width 0.508)
			(type default)
		)
		(layer "In1.Cu")
	)
	(gr_line
		(start 14.097 -16.129)
		(end 9.779 -20.447)
		(stroke
			(width 0.508)
			(type default)
		)
		(layer "In1.Cu")
	)
	(gr_line
		(start 14.224 -16.129)
		(end 14.097 -16.129)
		(stroke
			(width 0.508)
			(type default)
		)
		(layer "In1.Cu")
	)
	(gr_line
		(start 104.267 -49.149)
		(end 106.045 -47.371)
		(stroke
			(width 0.508)
			(type default)
		)
		(layer "In1.Cu")
	)
	(gr_line
		(start 106.045 -47.371)
		(end 140.97 -47.371)
		(stroke
			(width 0.508)
			(type default)
		)
		(layer "In1.Cu")
	)
	(gr_line
		(start 137.660126 -95.149924)
		(end 137.660126 -90.849958)
		(stroke
			(width 1.524)
			(type default)
		)
		(layer "In1.Cu")
	)
	(gr_arc
		(start 137.660126 -95.149924)
		(mid 137.953029 -95.857005)
		(end 138.660124 -96.149922)
		(stroke
			(width 1.524)
			(type default)
		)
		(layer "In1.Cu")
	)
	(gr_arc
		(start 138.660124 -89.84996)
		(mid 137.952988 -90.142842)
		(end 137.660126 -90.849958)
		(stroke
			(width 1.524)
			(type default)
		)
		(layer "In1.Cu")
	)
	(gr_line
		(start 138.660124 -89.84996)
		(end 159.357314 -89.84996)
		(stroke
			(width 1.524)
			(type default)
		)
		(layer "In1.Cu")
	)
	(gr_line
		(start 139.04976 -16.11376)
		(end 14.224 -16.129)
		(stroke
			(width 0.508)
			(type default)
		)
		(layer "In1.Cu")
	)
	(gr_line
		(start 140.97 -47.371)
		(end 143.891 -50.292)
		(stroke
			(width 0.508)
			(type default)
		)
		(layer "In1.Cu")
	)
	(gr_line
		(start 143.891 -50.292)
		(end 153.797 -50.292)
		(stroke
			(width 0.508)
			(type default)
		)
		(layer "In1.Cu")
	)
	(gr_line
		(start 149.86 -36.195)
		(end 149.86 -26.924)
		(stroke
			(width 0.508)
			(type default)
		)
		(layer "In1.Cu")
	)
	(gr_line
		(start 149.86 -26.924)
		(end 139.04976 -16.11376)
		(stroke
			(width 0.508)
			(type default)
		)
		(layer "In1.Cu")
	)
	(gr_line
		(start 153.797 -50.292)
		(end 154.559 -49.53)
		(stroke
			(width 0.508)
			(type default)
		)
		(layer "In1.Cu")
	)
	(gr_line
		(start 154.559 -49.53)
		(end 154.559 -40.894)
		(stroke
			(width 0.508)
			(type default)
		)
		(layer "In1.Cu")
	)
	(gr_line
		(start 154.559 -40.894)
		(end 149.86 -36.195)
		(stroke
			(width 0.508)
			(type default)
		)
		(layer "In1.Cu")
	)
	(gr_line
		(start 159.357314 -96.149922)
		(end 138.660124 -96.149922)
		(stroke
			(width 1.524)
			(type default)
		)
		(layer "In1.Cu")
	)
	(gr_arc
		(start 159.357314 -89.84996)
		(mid 159.646996 -89.807083)
		(end 159.911796 -89.682066)
		(stroke
			(width 1.524)
			(type default)
		)
		(layer "In1.Cu")
	)
	(gr_arc
		(start 159.911796 -96.31807)
		(mid 159.647 -96.192958)
		(end 159.357314 -96.149922)
		(stroke
			(width 1.524)
			(type default)
		)
		(layer "In1.Cu")
	)
	(gr_line
		(start 159.911796 -89.682066)
		(end 162.214814 -88.14689)
		(stroke
			(width 1.524)
			(type default)
		)
		(layer "In1.Cu")
	)
	(gr_arc
		(start 161.660078 -120.000014)
		(mid 162.367183 -119.707121)
		(end 162.660076 -119.000016)
		(stroke
			(width 1.524)
			(type default)
		)
		(layer "In1.Cu")
	)
	(gr_line
		(start 161.660078 0)
		(end 0.999998 0)
		(stroke
			(width 1.524)
			(type default)
		)
		(layer "In1.Cu")
	)
	(gr_line
		(start 162.214814 -97.853246)
		(end 159.911796 -96.31807)
		(stroke
			(width 1.524)
			(type default)
		)
		(layer "In1.Cu")
	)
	(gr_arc
		(start 162.214814 -88.14689)
		(mid 162.54181 -87.786674)
		(end 162.660076 -87.314786)
		(stroke
			(width 1.524)
			(type default)
		)
		(layer "In1.Cu")
	)
	(gr_line
		(start 162.660076 -119.000016)
		(end 162.660076 -98.685096)
		(stroke
			(width 1.524)
			(type default)
		)
		(layer "In1.Cu")
	)
	(gr_arc
		(start 162.660076 -98.685096)
		(mid 162.541691 -98.213381)
		(end 162.214814 -97.853246)
		(stroke
			(width 1.524)
			(type default)
		)
		(layer "In1.Cu")
	)
	(gr_line
		(start 162.660076 -87.314786)
		(end 162.660076 -0.999998)
		(stroke
			(width 1.524)
			(type default)
		)
		(layer "In1.Cu")
	)
	(gr_arc
		(start 162.660076 -0.999998)
		(mid 162.367183 -0.292893)
		(end 161.660078 0)
		(stroke
			(width 1.524)
			(type default)
		)
		(layer "In1.Cu")
	)
	(gr_line
		(start -10.999978 -91.45016)
		(end -9.500108 -92.95003)
		(stroke
			(width 2.54)
			(type default)
		)
		(layer "In2.Cu")
	)
	(gr_line
		(start -10.999978 -76.379832)
		(end -10.999978 -91.45016)
		(stroke
			(width 5.08)
			(type default)
		)
		(layer "In2.Cu")
	)
	(gr_line
		(start -10.999978 -72.680068)
		(end -9.500108 -74.179938)
		(stroke
			(width 2.54)
			(type default)
		)
		(layer "In2.Cu")
	)
	(gr_line
		(start -10.999978 -29.669994)
		(end -10.999978 -72.680068)
		(stroke
			(width 5.08)
			(type default)
		)
		(layer "In2.Cu")
	)
	(gr_line
		(start -9.500108 -92.95003)
		(end -0.999998 -92.95003)
		(stroke
			(width 2.54)
			(type default)
		)
		(layer "In2.Cu")
	)
	(gr_line
		(start -9.500108 -74.879962)
		(end -10.999978 -76.379832)
		(stroke
			(width 2.54)
			(type default)
		)
		(layer "In2.Cu")
	)
	(gr_line
		(start -9.500108 -74.179938)
		(end -0.350012 -74.179938)
		(stroke
			(width 2.54)
			(type default)
		)
		(layer "In2.Cu")
	)
	(gr_line
		(start -9.500108 -28.170124)
		(end -10.999978 -29.669994)
		(stroke
			(width 2.54)
			(type default)
		)
		(layer "In2.Cu")
	)
	(gr_line
		(start -0.999998 -28.170124)
		(end -9.500108 -28.170124)
		(stroke
			(width 2.54)
			(type default)
		)
		(layer "In2.Cu")
	)
	(gr_arc
		(start -0.999998 -28.170124)
		(mid -0.292893 -27.877231)
		(end 0 -27.170126)
		(stroke
			(width 2.54)
			(type default)
		)
		(layer "In2.Cu")
	)
	(gr_line
		(start -0.350012 -74.879962)
		(end -9.500108 -74.879962)
		(stroke
			(width 2.54)
			(type default)
		)
		(layer "In2.Cu")
	)
	(gr_arc
		(start -0.350012 -74.879962)
		(mid 0 -74.52995)
		(end -0.350012 -74.179938)
		(stroke
			(width 2.54)
			(type default)
		)
		(layer "In2.Cu")
	)
	(gr_arc
		(start 0 -119.000016)
		(mid 0.292893 -119.707121)
		(end 0.999998 -120.000014)
		(stroke
			(width 2.54)
			(type default)
		)
		(layer "In2.Cu")
	)
	(gr_arc
		(start 0 -93.950028)
		(mid -0.292893 -93.242923)
		(end -0.999998 -92.95003)
		(stroke
			(width 2.54)
			(type default)
		)
		(layer "In2.Cu")
	)
	(gr_line
		(start 0 -93.950028)
		(end 0 -119.000016)
		(stroke
			(width 2.54)
			(type default)
		)
		(layer "In2.Cu")
	)
	(gr_line
		(start 0 -0.999998)
		(end 0 -27.170126)
		(stroke
			(width 2.54)
			(type default)
		)
		(layer "In2.Cu")
	)
	(gr_line
		(start 0.254 -20.447)
		(end 9.779 -20.447)
		(stroke
			(width 0.508)
			(type default)
		)
		(layer "In2.Cu")
	)
	(gr_line
		(start 0.999998 -120.000014)
		(end 161.660078 -120.000014)
		(stroke
			(width 2.54)
			(type default)
		)
		(layer "In2.Cu")
	)
	(gr_arc
		(start 0.999998 0)
		(mid 0.292893 -0.292893)
		(end 0 -0.999998)
		(stroke
			(width 2.54)
			(type default)
		)
		(layer "In2.Cu")
	)
	(gr_line
		(start 9.779 -20.447)
		(end 14.097 -16.129)
		(stroke
			(width 0.508)
			(type default)
		)
		(layer "In2.Cu")
	)
	(gr_line
		(start 14.097 -16.129)
		(end 14.224 -16.129)
		(stroke
			(width 0.508)
			(type default)
		)
		(layer "In2.Cu")
	)
	(gr_line
		(start 14.224 -16.129)
		(end 139.04976 -16.11376)
		(stroke
			(width 0.508)
			(type default)
		)
		(layer "In2.Cu")
	)
	(gr_line
		(start 104.267 -49.149)
		(end -8.790178 -49.13376)
		(stroke
			(width 0.508)
			(type default)
		)
		(layer "In2.Cu")
	)
	(gr_line
		(start 106.045 -47.371)
		(end 104.267 -49.149)
		(stroke
			(width 0.508)
			(type default)
		)
		(layer "In2.Cu")
	)
	(gr_line
		(start 123.670822 -47.35576)
		(end 106.045 -47.371)
		(stroke
			(width 0.508)
			(type default)
		)
		(layer "In2.Cu")
	)
	(gr_line
		(start 137.660126 -95.149924)
		(end 137.660126 -90.849958)
		(stroke
			(width 2.54)
			(type default)
		)
		(layer "In2.Cu")
	)
	(gr_arc
		(start 137.660126 -95.149924)
		(mid 137.953029 -95.857005)
		(end 138.660124 -96.149922)
		(stroke
			(width 2.54)
			(type default)
		)
		(layer "In2.Cu")
	)
	(gr_arc
		(start 138.660124 -89.84996)
		(mid 137.952988 -90.142842)
		(end 137.660126 -90.849958)
		(stroke
			(width 2.54)
			(type default)
		)
		(layer "In2.Cu")
	)
	(gr_line
		(start 138.660124 -89.84996)
		(end 159.357314 -89.84996)
		(stroke
			(width 2.54)
			(type default)
		)
		(layer "In2.Cu")
	)
	(gr_line
		(start 139.04976 -16.11376)
		(end 149.86 -26.924)
		(stroke
			(width 0.508)
			(type default)
		)
		(layer "In2.Cu")
	)
	(gr_line
		(start 140.97 -47.371)
		(end 123.670822 -47.35576)
		(stroke
			(width 0.508)
			(type default)
		)
		(layer "In2.Cu")
	)
	(gr_line
		(start 143.891 -50.292)
		(end 140.97 -47.371)
		(stroke
			(width 0.508)
			(type default)
		)
		(layer "In2.Cu")
	)
	(gr_line
		(start 149.86 -36.195)
		(end 154.559 -40.894)
		(stroke
			(width 0.508)
			(type default)
		)
		(layer "In2.Cu")
	)
	(gr_line
		(start 149.86 -26.924)
		(end 149.86 -36.195)
		(stroke
			(width 0.508)
			(type default)
		)
		(layer "In2.Cu")
	)
	(gr_line
		(start 153.797 -50.292)
		(end 143.891 -50.292)
		(stroke
			(width 0.508)
			(type default)
		)
		(layer "In2.Cu")
	)
	(gr_line
		(start 154.559 -49.53)
		(end 153.797 -50.292)
		(stroke
			(width 0.508)
			(type default)
		)
		(layer "In2.Cu")
	)
	(gr_line
		(start 154.559 -40.894)
		(end 154.559 -49.53)
		(stroke
			(width 0.508)
			(type default)
		)
		(layer "In2.Cu")
	)
	(gr_line
		(start 159.357314 -96.149922)
		(end 138.660124 -96.149922)
		(stroke
			(width 2.54)
			(type default)
		)
		(layer "In2.Cu")
	)
	(gr_arc
		(start 159.357314 -89.84996)
		(mid 159.646996 -89.807083)
		(end 159.911796 -89.682066)
		(stroke
			(width 2.54)
			(type default)
		)
		(layer "In2.Cu")
	)
	(gr_arc
		(start 159.911796 -96.31807)
		(mid 159.647 -96.192958)
		(end 159.357314 -96.149922)
		(stroke
			(width 2.54)
			(type default)
		)
		(layer "In2.Cu")
	)
	(gr_line
		(start 159.911796 -89.682066)
		(end 162.214814 -88.14689)
		(stroke
			(width 2.54)
			(type default)
		)
		(layer "In2.Cu")
	)
	(gr_arc
		(start 161.660078 -120.000014)
		(mid 162.367183 -119.707121)
		(end 162.660076 -119.000016)
		(stroke
			(width 2.54)
			(type default)
		)
		(layer "In2.Cu")
	)
	(gr_line
		(start 161.660078 0)
		(end 0.999998 0)
		(stroke
			(width 2.54)
			(type default)
		)
		(layer "In2.Cu")
	)
	(gr_line
		(start 162.214814 -97.853246)
		(end 159.911796 -96.31807)
		(stroke
			(width 2.54)
			(type default)
		)
		(layer "In2.Cu")
	)
	(gr_arc
		(start 162.214814 -88.14689)
		(mid 162.54181 -87.786674)
		(end 162.660076 -87.314786)
		(stroke
			(width 2.54)
			(type default)
		)
		(layer "In2.Cu")
	)
	(gr_line
		(start 162.660076 -119.000016)
		(end 162.660076 -98.685096)
		(stroke
			(width 2.54)
			(type default)
		)
		(layer "In2.Cu")
	)
	(gr_arc
		(start 162.660076 -98.685096)
		(mid 162.541691 -98.213381)
		(end 162.214814 -97.853246)
		(stroke
			(width 2.54)
			(type default)
		)
		(layer "In2.Cu")
	)
	(gr_line
		(start 162.660076 -87.314786)
		(end 162.660076 -0.999998)
		(stroke
			(width 2.54)
			(type default)
		)
		(layer "In2.Cu")
	)
	(gr_arc
		(start 162.660076 -0.999998)
		(mid 162.367183 -0.292893)
		(end 161.660078 0)
		(stroke
			(width 2.54)
			(type default)
		)
		(layer "In2.Cu")
	)
	(gr_line
		(start -10.999978 -91.45016)
		(end -9.500108 -92.95003)
		(stroke
			(width 0.05)
			(type default)
		)
		(layer "Edge.Cuts")
	)
	(gr_line
		(start -10.999978 -76.379832)
		(end -10.999978 -91.45016)
		(stroke
			(width 0.05)
			(type default)
		)
		(layer "Edge.Cuts")
	)
	(gr_line
		(start -10.999978 -72.680068)
		(end -9.500108 -74.179938)
		(stroke
			(width 0.05)
			(type default)
		)
		(layer "Edge.Cuts")
	)
	(gr_line
		(start -10.999978 -29.669994)
		(end -10.999978 -72.680068)
		(stroke
			(width 0.05)
			(type default)
		)
		(layer "Edge.Cuts")
	)
	(gr_line
		(start -9.500108 -92.95003)
		(end -0.999998 -92.95003)
		(stroke
			(width 0.05)
			(type default)
		)
		(layer "Edge.Cuts")
	)
	(gr_line
		(start -9.500108 -74.879962)
		(end -10.999978 -76.379832)
		(stroke
			(width 0.05)
			(type default)
		)
		(layer "Edge.Cuts")
	)
	(gr_line
		(start -9.500108 -74.179938)
		(end -0.350012 -74.179938)
		(stroke
			(width 0.05)
			(type default)
		)
		(layer "Edge.Cuts")
	)
	(gr_line
		(start -9.500108 -28.170124)
		(end -10.999978 -29.669994)
		(stroke
			(width 0.05)
			(type default)
		)
		(layer "Edge.Cuts")
	)
	(gr_line
		(start -0.999998 -28.170124)
		(end -9.500108 -28.170124)
		(stroke
			(width 0.05)
			(type default)
		)
		(layer "Edge.Cuts")
	)
	(gr_arc
		(start -0.999998 -28.170124)
		(mid -0.292893 -27.877231)
		(end 0 -27.170126)
		(stroke
			(width 0.05)
			(type default)
		)
		(layer "Edge.Cuts")
	)
	(gr_line
		(start -0.350012 -74.879962)
		(end -9.500108 -74.879962)
		(stroke
			(width 0.05)
			(type default)
		)
		(layer "Edge.Cuts")
	)
	(gr_arc
		(start -0.350012 -74.879962)
		(mid 0 -74.52995)
		(end -0.350012 -74.179938)
		(stroke
			(width 0.05)
			(type default)
		)
		(layer "Edge.Cuts")
	)
	(gr_arc
		(start 0 -119.000016)
		(mid 0.292893 -119.707121)
		(end 0.999998 -120.000014)
		(stroke
			(width 0.05)
			(type default)
		)
		(layer "Edge.Cuts")
	)
	(gr_arc
		(start 0 -93.950028)
		(mid -0.292893 -93.242923)
		(end -0.999998 -92.95003)
		(stroke
			(width 0.05)
			(type default)
		)
		(layer "Edge.Cuts")
	)
	(gr_line
		(start 0 -93.950028)
		(end 0 -119.000016)
		(stroke
			(width 0.05)
			(type default)
		)
		(layer "Edge.Cuts")
	)
	(gr_line
		(start 0 -0.999998)
		(end 0 -27.170126)
		(stroke
			(width 0.05)
			(type default)
		)
		(layer "Edge.Cuts")
	)
	(gr_line
		(start 0.999998 -120.000014)
		(end 161.660078 -120.000014)
		(stroke
			(width 0.05)
			(type default)
		)
		(layer "Edge.Cuts")
	)
	(gr_arc
		(start 0.999998 0)
		(mid 0.292893 -0.292893)
		(end 0 -0.999998)
		(stroke
			(width 0.05)
			(type default)
		)
		(layer "Edge.Cuts")
	)
	(gr_arc
		(start 4.379976 -62.500002)
		(mid 4.672869 -63.207107)
		(end 5.379974 -63.5)
		(stroke
			(width 0.05)
			(type default)
		)
		(layer "Edge.Cuts")
	)
	(gr_line
		(start 4.379976 -57.500012)
		(end 4.379976 -62.500002)
		(stroke
			(width 0.05)
			(type default)
		)
		(layer "Edge.Cuts")
	)
	(gr_line
		(start 5.379974 -63.5)
		(end 6.379972 -63.5)
		(stroke
			(width 0.05)
			(type default)
		)
		(layer "Edge.Cuts")
	)
	(gr_arc
		(start 5.379974 -56.500014)
		(mid 4.672869 -56.792907)
		(end 4.379976 -57.500012)
		(stroke
			(width 0.05)
			(type default)
		)
		(layer "Edge.Cuts")
	)
	(gr_arc
		(start 6.379972 -63.5)
		(mid 7.087077 -63.207107)
		(end 7.37997 -62.500002)
		(stroke
			(width 0.05)
			(type default)
		)
		(layer "Edge.Cuts")
	)
	(gr_line
		(start 6.379972 -56.500014)
		(end 5.379974 -56.500014)
		(stroke
			(width 0.05)
			(type default)
		)
		(layer "Edge.Cuts")
	)
	(gr_line
		(start 7.37997 -62.500002)
		(end 7.37997 -57.500012)
		(stroke
			(width 0.05)
			(type default)
		)
		(layer "Edge.Cuts")
	)
	(gr_arc
		(start 7.37997 -57.500012)
		(mid 7.087077 -56.792907)
		(end 6.379972 -56.500014)
		(stroke
			(width 0.05)
			(type default)
		)
		(layer "Edge.Cuts")
	)
	(gr_line
		(start 137.660126 -95.149924)
		(end 137.660126 -90.849958)
		(stroke
			(width 0.05)
			(type default)
		)
		(layer "Edge.Cuts")
	)
	(gr_arc
		(start 137.660126 -95.149924)
		(mid 137.953029 -95.857005)
		(end 138.660124 -96.149922)
		(stroke
			(width 0.05)
			(type default)
		)
		(layer "Edge.Cuts")
	)
	(gr_arc
		(start 138.660124 -89.84996)
		(mid 137.952988 -90.142842)
		(end 137.660126 -90.849958)
		(stroke
			(width 0.05)
			(type default)
		)
		(layer "Edge.Cuts")
	)
	(gr_line
		(start 138.660124 -89.84996)
		(end 159.357314 -89.84996)
		(stroke
			(width 0.05)
			(type default)
		)
		(layer "Edge.Cuts")
	)
	(gr_line
		(start 157.660086 -79.462884)
		(end 157.660086 -34.536888)
		(stroke
			(width 0.05)
			(type default)
		)
		(layer "Edge.Cuts")
	)
	(gr_arc
		(start 157.660086 -79.462884)
		(mid 157.952972 -80.170005)
		(end 158.660084 -80.462882)
		(stroke
			(width 0.05)
			(type default)
		)
		(layer "Edge.Cuts")
	)
	(gr_arc
		(start 158.660084 -33.53689)
		(mid 157.952985 -33.829788)
		(end 157.660086 -34.536888)
		(stroke
			(width 0.05)
			(type default)
		)
		(layer "Edge.Cuts")
	)
	(gr_line
		(start 158.660084 -33.53689)
		(end 161.660078 -33.53689)
		(stroke
			(width 0.05)
			(type default)
		)
		(layer "Edge.Cuts")
	)
	(gr_line
		(start 159.357314 -96.149922)
		(end 138.660124 -96.149922)
		(stroke
			(width 0.05)
			(type default)
		)
		(layer "Edge.Cuts")
	)
	(gr_arc
		(start 159.357314 -89.84996)
		(mid 159.646996 -89.807083)
		(end 159.911796 -89.682066)
		(stroke
			(width 0.05)
			(type default)
		)
		(layer "Edge.Cuts")
	)
	(gr_arc
		(start 159.911796 -96.31807)
		(mid 159.647 -96.192958)
		(end 159.357314 -96.149922)
		(stroke
			(width 0.05)
			(type default)
		)
		(layer "Edge.Cuts")
	)
	(gr_line
		(start 159.911796 -89.682066)
		(end 162.214814 -88.14689)
		(stroke
			(width 0.05)
			(type default)
		)
		(layer "Edge.Cuts")
	)
	(gr_arc
		(start 161.660078 -120.000014)
		(mid 162.367183 -119.707121)
		(end 162.660076 -119.000016)
		(stroke
			(width 0.05)
			(type default)
		)
		(layer "Edge.Cuts")
	)
	(gr_line
		(start 161.660078 -80.462882)
		(end 158.660084 -80.462882)
		(stroke
			(width 0.05)
			(type default)
		)
		(layer "Edge.Cuts")
	)
	(gr_arc
		(start 161.660078 -33.53689)
		(mid 162.367183 -33.243997)
		(end 162.660076 -32.536892)
		(stroke
			(width 0.05)
			(type default)
		)
		(layer "Edge.Cuts")
	)
	(gr_arc
		(start 161.660078 -33.53689)
		(mid 162.367195 -33.244005)
		(end 162.660076 -32.536892)
		(stroke
			(width 0.05)
			(type default)
		)
		(layer "Edge.Cuts")
	)
	(gr_line
		(start 161.660078 0)
		(end 0.999998 0)
		(stroke
			(width 0.05)
			(type default)
		)
		(layer "Edge.Cuts")
	)
	(gr_line
		(start 162.214814 -97.853246)
		(end 159.911796 -96.31807)
		(stroke
			(width 0.05)
			(type default)
		)
		(layer "Edge.Cuts")
	)
	(gr_arc
		(start 162.214814 -88.14689)
		(mid 162.54181 -87.786674)
		(end 162.660076 -87.314786)
		(stroke
			(width 0.05)
			(type default)
		)
		(layer "Edge.Cuts")
	)
	(gr_line
		(start 162.660076 -119.000016)
		(end 162.660076 -98.685096)
		(stroke
			(width 0.05)
			(type default)
		)
		(layer "Edge.Cuts")
	)
	(gr_arc
		(start 162.660076 -98.685096)
		(mid 162.541691 -98.213381)
		(end 162.214814 -97.853246)
		(stroke
			(width 0.05)
			(type default)
		)
		(layer "Edge.Cuts")
	)
	(gr_line
		(start 162.660076 -87.314786)
		(end 162.660076 -81.46288)
		(stroke
			(width 0.05)
			(type default)
		)
		(layer "Edge.Cuts")
	)
	(gr_arc
		(start 162.660076 -81.46288)
		(mid 162.367183 -80.755775)
		(end 161.660078 -80.462882)
		(stroke
			(width 0.05)
			(type default)
		)
		(layer "Edge.Cuts")
	)
	(gr_line
		(start 162.660076 -32.536892)
		(end 162.660076 -0.999998)
		(stroke
			(width 0.05)
			(type default)
		)
		(layer "Edge.Cuts")
	)
	(gr_arc
		(start 162.660076 -0.999998)
		(mid 162.367181 -0.292902)
		(end 161.660078 0)
		(stroke
			(width 0.05)
			(type default)
		)
		(layer "Edge.Cuts")
	)
	(gr_arc
		(start 162.660076 -0.999998)
		(mid 162.367183 -0.292893)
		(end 161.660078 0)
		(stroke
			(width 0.05)
			(type default)
		)
		(layer "Edge.Cuts")
	)
	(gr_line
		(start 162.660076 -0.999998)
		(end 162.660076 -32.536892)
		(stroke
			(width 0.05)
			(type default)
		)
		(layer "Edge.Cuts")
	)
	(segment
		(start 151.407114 -16.997172)
		(end 151.409908 -16.999966)
		(width 0.1397)
		(layer "F.Cu")
		(net "TPS2490_DISABLE")
	)
	(segment
		(start 147.613878 -16.997172)
		(end 151.407114 -16.997172)
		(width 0.1397)
		(layer "F.Cu")
		(net "TPS2490_DISABLE")
	)
	(segment
		(start 7.634732 -93.708728)
		(end 6.617208 -93.708728)
		(width 0.1397)
		(layer "F.Cu")
		(net "STRADDLE_I2C_C_SCL")
	)
	(segment
		(start 5.940044 -91.794838)
		(end 1.446276 -87.30107)
		(width 0.1397)
		(layer "F.Cu")
		(net "STRADDLE_I2C_C_SCL")
	)
	(segment
		(start 5.940044 -93.031564)
		(end 5.940044 -91.794838)
		(width 0.1397)
		(layer "F.Cu")
		(net "STRADDLE_I2C_C_SCL")
	)
	(segment
		(start 6.617208 -93.708728)
		(end 5.940044 -93.031564)
		(width 0.1397)
		(layer "F.Cu")
		(net "STRADDLE_I2C_C_SCL")
	)
	(via
		(at 1.446276 -87.30107)
		(size 0.7112)
		(drill 0.4064)
		(layers "F.Cu" "B.Cu")
		(net "STRADDLE_I2C_C_SCL")
	)
	(via
		(at 0.41529 -88.332056)
		(size 0.7112)
		(drill 0.3556)
		(layers "F.Cu" "B.Cu")
		(net "STRADDLE_I2C_C_SCL")
	)
	(segment
		(start -0.711962 -89.459308)
		(end 0.41529 -88.332056)
		(width 0.1397)
		(layer "B.Cu")
		(net "STRADDLE_I2C_C_SCL")
	)
	(segment
		(start 1.446276 -87.30107)
		(end 0.41529 -88.332056)
		(width 0.1397)
		(layer "B.Cu")
		(net "STRADDLE_I2C_C_SCL")
	)
	(segment
		(start -6.61797 -89.459308)
		(end -0.711962 -89.459308)
		(width 0.1397)
		(layer "B.Cu")
		(net "STRADDLE_I2C_C_SCL")
	)
	(segment
		(start 6.966204 -95.029528)
		(end 5.094478 -93.157802)
		(width 0.1397)
		(layer "F.Cu")
		(net "STRADDLE_I2C_C_SDA")
	)
	(segment
		(start 5.094478 -93.157802)
		(end 5.094478 -92.016072)
		(width 0.1397)
		(layer "F.Cu")
		(net "STRADDLE_I2C_C_SDA")
	)
	(segment
		(start 7.634732 -95.029528)
		(end 6.966204 -95.029528)
		(width 0.1397)
		(layer "F.Cu")
		(net "STRADDLE_I2C_C_SDA")
	)
	(segment
		(start 5.094478 -92.016072)
		(end 0.379476 -87.30107)
		(width 0.1397)
		(layer "F.Cu")
		(net "STRADDLE_I2C_C_SDA")
	)
	(via
		(at 0.379476 -87.30107)
		(size 0.7112)
		(drill 0.4064)
		(layers "F.Cu" "B.Cu")
		(net "STRADDLE_I2C_C_SDA")
	)
	(via
		(at -0.691388 -86.614)
		(size 0.7112)
		(drill 0.3556)
		(layers "F.Cu" "B.Cu")
		(net "STRADDLE_I2C_C_SDA")
	)
	(segment
		(start -0.307594 -86.614)
		(end -0.691388 -86.614)
		(width 0.1397)
		(layer "B.Cu")
		(net "STRADDLE_I2C_C_SDA")
	)
	(segment
		(start -2.869692 -86.614)
		(end -0.691388 -86.614)
		(width 0.1397)
		(layer "B.Cu")
		(net "STRADDLE_I2C_C_SDA")
	)
	(segment
		(start -3.175 -86.919308)
		(end -2.869692 -86.614)
		(width 0.1397)
		(layer "B.Cu")
		(net "STRADDLE_I2C_C_SDA")
	)
	(segment
		(start 0.379476 -87.30107)
		(end -0.307594 -86.614)
		(width 0.1397)
		(layer "B.Cu")
		(net "STRADDLE_I2C_C_SDA")
	)
	(segment
		(start -6.61797 -86.919308)
		(end -3.175 -86.919308)
		(width 0.1397)
		(layer "B.Cu")
		(net "STRADDLE_I2C_C_SDA")
	)
	(segment
		(start 15.952216 -95.23476)
		(end 14.148054 -95.23476)
		(width 0.1397)
		(layer "F.Cu")
		(net "I2C_C_BUF_SDAIN")
	)
	(segment
		(start 16.7894 -97.411032)
		(end 16.7894 -96.071944)
		(width 0.1397)
		(layer "F.Cu")
		(net "I2C_C_BUF_SDAIN")
	)
	(segment
		(start 13.975588 -95.407226)
		(end 13.975588 -96.431608)
		(width 0.1397)
		(layer "F.Cu")
		(net "I2C_C_BUF_SDAIN")
	)
	(segment
		(start 14.059408 -97.978214)
		(end 13.975588 -97.894394)
		(width 0.1397)
		(layer "F.Cu")
		(net "I2C_C_BUF_SDAIN")
	)
	(segment
		(start 14.059408 -98.380296)
		(end 14.059408 -97.978214)
		(width 0.1397)
		(layer "F.Cu")
		(net "I2C_C_BUF_SDAIN")
	)
	(segment
		(start 16.7894 -96.071944)
		(end 15.952216 -95.23476)
		(width 0.1397)
		(layer "F.Cu")
		(net "I2C_C_BUF_SDAIN")
	)
	(segment
		(start 14.148054 -95.23476)
		(end 13.975588 -95.407226)
		(width 0.1397)
		(layer "F.Cu")
		(net "I2C_C_BUF_SDAIN")
	)
	(segment
		(start 13.975588 -97.894394)
		(end 13.975588 -96.431608)
		(width 0.1397)
		(layer "F.Cu")
		(net "I2C_C_BUF_SDAIN")
	)
	(via
		(at 16.7894 -97.411032)
		(size 0.7112)
		(drill 0.3556)
		(layers "F.Cu" "B.Cu")
		(net "I2C_C_BUF_SDAIN")
	)
	(segment
		(start 13.163804 -95.30461)
		(end 13.325348 -95.466154)
		(width 0.1397)
		(layer "F.Cu")
		(net "I2C_C_BUF_SDAOUT")
	)
	(segment
		(start 12.977876 -98.36785)
		(end 13.325348 -98.020378)
		(width 0.1397)
		(layer "F.Cu")
		(net "I2C_C_BUF_SDAOUT")
	)
	(segment
		(start 10.962386 -97.182178)
		(end 10.962386 -95.84309)
		(width 0.1397)
		(layer "F.Cu")
		(net "I2C_C_BUF_SDAOUT")
	)
	(segment
		(start 13.325348 -95.466154)
		(end 13.325348 -96.431608)
		(width 0.1397)
		(layer "F.Cu")
		(net "I2C_C_BUF_SDAOUT")
	)
	(segment
		(start 13.325348 -98.020378)
		(end 13.325348 -96.431608)
		(width 0.1397)
		(layer "F.Cu")
		(net "I2C_C_BUF_SDAOUT")
	)
	(segment
		(start 11.500866 -95.30461)
		(end 13.163804 -95.30461)
		(width 0.1397)
		(layer "F.Cu")
		(net "I2C_C_BUF_SDAOUT")
	)
	(segment
		(start 10.962386 -95.84309)
		(end 11.500866 -95.30461)
		(width 0.1397)
		(layer "F.Cu")
		(net "I2C_C_BUF_SDAOUT")
	)
	(via
		(at 10.962386 -97.182178)
		(size 0.7112)
		(drill 0.3556)
		(layers "F.Cu" "B.Cu")
		(net "I2C_C_BUF_SDAOUT")
	)
	(segment
		(start 13.975588 -93.21927)
		(end 13.975588 -92.291408)
		(width 0.1397)
		(layer "F.Cu")
		(net "I2C_C_BUF_SCLIN")
	)
	(segment
		(start 16.774414 -92.751402)
		(end 16.10487 -93.420946)
		(width 0.1397)
		(layer "F.Cu")
		(net "I2C_C_BUF_SCLIN")
	)
	(segment
		(start 14.177264 -93.420946)
		(end 13.975588 -93.21927)
		(width 0.1397)
		(layer "F.Cu")
		(net "I2C_C_BUF_SCLIN")
	)
	(segment
		(start 16.10487 -93.420946)
		(end 14.177264 -93.420946)
		(width 0.1397)
		(layer "F.Cu")
		(net "I2C_C_BUF_SCLIN")
	)
	(segment
		(start 14.579092 -90.40114)
		(end 13.975588 -91.004644)
		(width 0.1397)
		(layer "F.Cu")
		(net "I2C_C_BUF_SCLIN")
	)
	(segment
		(start 16.774414 -91.412314)
		(end 16.774414 -92.751402)
		(width 0.1397)
		(layer "F.Cu")
		(net "I2C_C_BUF_SCLIN")
	)
	(segment
		(start 13.975588 -91.004644)
		(end 13.975588 -92.291408)
		(width 0.1397)
		(layer "F.Cu")
		(net "I2C_C_BUF_SCLIN")
	)
	(via
		(at 16.774414 -91.412314)
		(size 0.7112)
		(drill 0.3556)
		(layers "F.Cu" "B.Cu")
		(net "I2C_C_BUF_SCLIN")
	)
	(segment
		(start 10.940288 -92.912438)
		(end 11.51128 -93.48343)
		(width 0.1397)
		(layer "F.Cu")
		(net "I2C_C_BUF_SCLOUT")
	)
	(segment
		(start 11.51128 -93.48343)
		(end 13.067538 -93.48343)
		(width 0.1397)
		(layer "F.Cu")
		(net "I2C_C_BUF_SCLOUT")
	)
	(segment
		(start 13.38707 -90.38463)
		(end 13.38707 -91.044776)
		(width 0.1397)
		(layer "F.Cu")
		(net "I2C_C_BUF_SCLOUT")
	)
	(segment
		(start 10.940288 -91.57335)
		(end 10.940288 -92.912438)
		(width 0.1397)
		(layer "F.Cu")
		(net "I2C_C_BUF_SCLOUT")
	)
	(segment
		(start 13.325348 -91.106498)
		(end 13.325348 -92.291408)
		(width 0.1397)
		(layer "F.Cu")
		(net "I2C_C_BUF_SCLOUT")
	)
	(segment
		(start 13.38707 -91.044776)
		(end 13.325348 -91.106498)
		(width 0.1397)
		(layer "F.Cu")
		(net "I2C_C_BUF_SCLOUT")
	)
	(segment
		(start 13.067538 -93.48343)
		(end 13.325348 -93.22562)
		(width 0.1397)
		(layer "F.Cu")
		(net "I2C_C_BUF_SCLOUT")
	)
	(segment
		(start 13.325348 -93.22562)
		(end 13.325348 -92.291408)
		(width 0.1397)
		(layer "F.Cu")
		(net "I2C_C_BUF_SCLOUT")
	)
	(via
		(at 10.940288 -91.57335)
		(size 0.7112)
		(drill 0.3556)
		(layers "F.Cu" "B.Cu")
		(net "I2C_C_BUF_SCLOUT")
	)
	(segment
		(start 153.543 -66.167)
		(end 153.543 -63.0428)
		(width 0.1397)
		(layer "F.Cu")
		(net "PWM_EXP_B_OUT")
	)
	(segment
		(start 143.637 -66.802)
		(end 152.908 -66.802)
		(width 0.1397)
		(layer "F.Cu")
		(net "PWM_EXP_B_OUT")
	)
	(segment
		(start 31.922466 -81.691226)
		(end 111.65459 -81.691226)
		(width 0.1397)
		(layer "F.Cu")
		(net "PWM_EXP_B_OUT")
	)
	(segment
		(start 119.398542 -81.691226)
		(end 136.866884 -64.222884)
		(width 0.1397)
		(layer "F.Cu")
		(net "PWM_EXP_B_OUT")
	)
	(segment
		(start 153.543 -63.0428)
		(end 152.580086 -62.079886)
		(width 0.1397)
		(layer "F.Cu")
		(net "PWM_EXP_B_OUT")
	)
	(segment
		(start 111.65459 -81.691226)
		(end 119.398542 -81.691226)
		(width 0.1397)
		(layer "F.Cu")
		(net "PWM_EXP_B_OUT")
	)
	(segment
		(start 152.908 -66.802)
		(end 153.543 -66.167)
		(width 0.1397)
		(layer "F.Cu")
		(net "PWM_EXP_B_OUT")
	)
	(segment
		(start 141.057884 -64.222884)
		(end 143.637 -66.802)
		(width 0.1397)
		(layer "F.Cu")
		(net "PWM_EXP_B_OUT")
	)
	(segment
		(start 10.636504 -85.835744)
		(end 11.536426 -84.935822)
		(width 0.1397)
		(layer "F.Cu")
		(net "PWM_EXP_B_OUT")
	)
	(segment
		(start 11.536426 -84.935822)
		(end 28.67787 -84.935822)
		(width 0.1397)
		(layer "F.Cu")
		(net "PWM_EXP_B_OUT")
	)
	(segment
		(start 9.816592 -85.835744)
		(end 10.636504 -85.835744)
		(width 0.1397)
		(layer "F.Cu")
		(net "PWM_EXP_B_OUT")
	)
	(segment
		(start 28.67787 -84.935822)
		(end 31.922466 -81.691226)
		(width 0.1397)
		(layer "F.Cu")
		(net "PWM_EXP_B_OUT")
	)
	(segment
		(start 136.866884 -64.222884)
		(end 141.057884 -64.222884)
		(width 0.1397)
		(layer "F.Cu")
		(net "PWM_EXP_B_OUT")
	)
	(via
		(at 111.65459 -81.691226)
		(size 0.7112)
		(drill 0.3556)
		(layers "F.Cu" "B.Cu")
		(net "PWM_EXP_B_OUT")
	)
	(segment
		(start 138.1506 -79.756)
		(end 138.176 -79.756)
		(width 0.508)
		(layer "F.Cu")
		(net "P3V3")
	)
	(segment
		(start 132.207 -83.566)
		(end 132.7785 -82.9945)
		(width 0.508)
		(layer "F.Cu")
		(net "P3V3")
	)
	(segment
		(start 13.38707 -89.49563)
		(end 13.38707 -88.551004)
		(width 0.508)
		(layer "F.Cu")
		(net "P3V3")
	)
	(segment
		(start 155.650692 -103.844344)
		(end 155.650692 -104.902)
		(width 0.762)
		(layer "F.Cu")
		(net "P3V3")
	)
	(segment
		(start 11.544808 -98.428302)
		(end 11.634978 -98.518472)
		(width 0.508)
		(layer "F.Cu")
		(net "P3V3")
	)
	(segment
		(start 14.579092 -89.51214)
		(end 14.579092 -88.565228)
		(width 0.508)
		(layer "F.Cu")
		(net "P3V3")
	)
	(segment
		(start 12.409932 -97.743518)
		(end 12.675108 -97.478342)
		(width 0.3556)
		(layer "F.Cu")
		(net "P3V3")
	)
	(segment
		(start 12.27455 -89.5096)
		(end 12.27455 -88.522556)
		(width 0.508)
		(layer "F.Cu")
		(net "P3V3")
	)
	(segment
		(start 132.7785 -82.9945)
		(end 132.7785 -82.804)
		(width 0.508)
		(layer "F.Cu")
		(net "P3V3")
	)
	(segment
		(start 11.634978 -98.518472)
		(end 12.409932 -97.743518)
		(width 0.508)
		(layer "F.Cu")
		(net "P3V3")
	)
	(segment
		(start 9.782302 -98.428302)
		(end 10.492486 -98.428302)
		(width 0.508)
		(layer "F.Cu")
		(net "P3V3")
	)
	(segment
		(start 10.492486 -98.428302)
		(end 11.544808 -98.428302)
		(width 0.508)
		(layer "F.Cu")
		(net "P3V3")
	)
	(segment
		(start 138.176 -77.978)
		(end 136.652 -76.454)
		(width 0.508)
		(layer "F.Cu")
		(net "P3V3")
	)
	(segment
		(start 12.977876 -99.25685)
		(end 12.977876 -100.197412)
		(width 0.508)
		(layer "F.Cu")
		(net "P3V3")
	)
	(segment
		(start 138.176 -79.756)
		(end 138.176 -77.978)
		(width 0.508)
		(layer "F.Cu")
		(net "P3V3")
	)
	(segment
		(start 14.059408 -99.269296)
		(end 14.059408 -100.247196)
		(width 0.508)
		(layer "F.Cu")
		(net "P3V3")
	)
	(segment
		(start 15.253208 -99.248468)
		(end 15.253208 -100.247196)
		(width 0.508)
		(layer "F.Cu")
		(net "P3V3")
	)
	(segment
		(start 132.207 -84.074)
		(end 132.207 -83.566)
		(width 0.508)
		(layer "F.Cu")
		(net "P3V3")
	)
	(segment
		(start 9.525 -98.171)
		(end 9.782302 -98.428302)
		(width 0.508)
		(layer "F.Cu")
		(net "P3V3")
	)
	(segment
		(start 12.675108 -97.478342)
		(end 12.675108 -96.431608)
		(width 0.3556)
		(layer "F.Cu")
		(net "P3V3")
	)
	(segment
		(start 136.652 -76.454)
		(end 136.652 -75.3745)
		(width 0.508)
		(layer "F.Cu")
		(net "P3V3")
	)
	(via
		(at 14.059408 -100.247196)
		(size 0.7112)
		(drill 0.4064)
		(layers "F.Cu" "B.Cu")
		(net "P3V3")
	)
	(via
		(at 152.4 -86.868)
		(size 0.7112)
		(drill 0.4064)
		(layers "F.Cu" "B.Cu")
		(net "P3V3")
	)
	(via
		(at 12.977876 -100.197412)
		(size 0.7112)
		(drill 0.4064)
		(layers "F.Cu" "B.Cu")
		(net "P3V3")
	)
	(via
		(at 12.547092 -82.914744)
		(size 0.7112)
		(drill 0.3556)
		(layers "F.Cu" "B.Cu")
		(net "P3V3")
	)
	(via
		(at 15.253208 -100.247196)
		(size 0.7112)
		(drill 0.4064)
		(layers "F.Cu" "B.Cu")
		(net "P3V3")
	)
	(via
		(at 13.563092 -98.789744)
		(size 0.7112)
		(drill 0.3556)
		(layers "F.Cu" "B.Cu")
		(net "P3V3")
	)
	(via
		(at 147.193 -84.709)
		(size 0.7112)
		(drill 0.3556)
		(layers "F.Cu" "B.Cu")
		(net "P3V3")
	)
	(via
		(at 9.525 -98.171)
		(size 0.7112)
		(drill 0.4064)
		(layers "F.Cu" "B.Cu")
		(net "P3V3")
	)
	(via
		(at 152.4 -85.725)
		(size 0.7112)
		(drill 0.4064)
		(layers "F.Cu" "B.Cu")
		(net "P3V3")
	)
	(via
		(at 151.257 -85.725)
		(size 0.7112)
		(drill 0.4064)
		(layers "F.Cu" "B.Cu")
		(net "P3V3")
	)
	(via
		(at 13.38707 -88.551004)
		(size 0.7112)
		(drill 0.4064)
		(layers "F.Cu" "B.Cu")
		(net "P3V3")
	)
	(via
		(at 155.650692 -104.902)
		(size 0.7112)
		(drill 0.4064)
		(layers "F.Cu" "B.Cu")
		(net "P3V3")
	)
	(via
		(at 132.207 -84.074)
		(size 0.7112)
		(drill 0.4064)
		(layers "F.Cu" "B.Cu")
		(net "P3V3")
	)
	(via
		(at 138.1506 -79.756)
		(size 0.7112)
		(drill 0.4064)
		(layers "F.Cu" "B.Cu")
		(net "P3V3")
	)
	(via
		(at 12.27455 -88.522556)
		(size 0.7112)
		(drill 0.4064)
		(layers "F.Cu" "B.Cu")
		(net "P3V3")
	)
	(via
		(at 14.579092 -88.565228)
		(size 0.7112)
		(drill 0.4064)
		(layers "F.Cu" "B.Cu")
		(net "P3V3")
	)
	(via
		(at 153.771092 -103.996744)
		(size 0.7112)
		(drill 0.3556)
		(layers "F.Cu" "B.Cu")
		(net "P3V3")
	)
	(via
		(at 151.257 -86.868)
		(size 0.7112)
		(drill 0.4064)
		(layers "F.Cu" "B.Cu")
		(net "P3V3")
	)
	(via
		(at 5.181092 -78.723744)
		(size 0.7112)
		(drill 0.3556)
		(layers "F.Cu" "B.Cu")
		(net "P3V3")
	)
	(segment
		(start 119.322342 -81.138776)
		(end 44.897548 -81.138776)
		(width 0.1397)
		(layer "F.Cu")
		(net "PWM_EXP_A_OUT")
	)
	(segment
		(start 136.682734 -63.778384)
		(end 119.322342 -81.138776)
		(width 0.1397)
		(layer "F.Cu")
		(net "PWM_EXP_A_OUT")
	)
	(segment
		(start 11.150092 -84.692744)
		(end 11.351514 -84.491322)
		(width 0.1397)
		(layer "F.Cu")
		(net "PWM_EXP_A_OUT")
	)
	(segment
		(start 144.018 -66.3575)
		(end 141.438884 -63.778384)
		(width 0.1397)
		(layer "F.Cu")
		(net "PWM_EXP_A_OUT")
	)
	(segment
		(start 31.846266 -81.138776)
		(end 44.897548 -81.138776)
		(width 0.1397)
		(layer "F.Cu")
		(net "PWM_EXP_A_OUT")
	)
	(segment
		(start 151.511 -65.532)
		(end 150.6855 -66.3575)
		(width 0.1397)
		(layer "F.Cu")
		(net "PWM_EXP_A_OUT")
	)
	(segment
		(start 151.511 -55.9308)
		(end 151.511 -65.532)
		(width 0.1397)
		(layer "F.Cu")
		(net "PWM_EXP_A_OUT")
	)
	(segment
		(start 28.49372 -84.491322)
		(end 31.846266 -81.138776)
		(width 0.1397)
		(layer "F.Cu")
		(net "PWM_EXP_A_OUT")
	)
	(segment
		(start 150.6855 -66.3575)
		(end 144.018 -66.3575)
		(width 0.1397)
		(layer "F.Cu")
		(net "PWM_EXP_A_OUT")
	)
	(segment
		(start 9.816592 -84.692744)
		(end 11.150092 -84.692744)
		(width 0.1397)
		(layer "F.Cu")
		(net "PWM_EXP_A_OUT")
	)
	(segment
		(start 141.438884 -63.778384)
		(end 136.682734 -63.778384)
		(width 0.1397)
		(layer "F.Cu")
		(net "PWM_EXP_A_OUT")
	)
	(segment
		(start 150.040086 -54.459886)
		(end 151.511 -55.9308)
		(width 0.1397)
		(layer "F.Cu")
		(net "PWM_EXP_A_OUT")
	)
	(segment
		(start 11.351514 -84.491322)
		(end 28.49372 -84.491322)
		(width 0.1397)
		(layer "F.Cu")
		(net "PWM_EXP_A_OUT")
	)
	(via
		(at 44.897548 -81.138776)
		(size 0.7112)
		(drill 0.3556)
		(layers "F.Cu" "B.Cu")
		(net "PWM_EXP_A_OUT")
	)
	(segment
		(start 24.110696 -81.454498)
		(end 25.215088 -81.454498)
		(width 0.1397)
		(layer "F.Cu")
		(net "SD_LATCH_RELEASE")
	)
	(segment
		(start 24.110442 -81.454244)
		(end 24.110696 -81.454498)
		(width 0.1397)
		(layer "F.Cu")
		(net "SD_LATCH_RELEASE")
	)
	(segment
		(start 118.865142 -77.824076)
		(end 101.996494 -77.824076)
		(width 0.1397)
		(layer "F.Cu")
		(net "SD_LATCH_RELEASE")
	)
	(segment
		(start 136.430004 -60.259214)
		(end 118.865142 -77.824076)
		(width 0.1397)
		(layer "F.Cu")
		(net "SD_LATCH_RELEASE")
	)
	(segment
		(start 28.84551 -77.824076)
		(end 101.996494 -77.824076)
		(width 0.1397)
		(layer "F.Cu")
		(net "SD_LATCH_RELEASE")
	)
	(segment
		(start 0.993394 -83.693)
		(end 3.23215 -81.454244)
		(width 0.1397)
		(layer "F.Cu")
		(net "SD_LATCH_RELEASE")
	)
	(segment
		(start 144.240758 -60.259214)
		(end 136.430004 -60.259214)
		(width 0.1397)
		(layer "F.Cu")
		(net "SD_LATCH_RELEASE")
	)
	(segment
		(start -6.99897 -84.379308)
		(end -0.535178 -84.379308)
		(width 0.1397)
		(layer "F.Cu")
		(net "SD_LATCH_RELEASE")
	)
	(segment
		(start -0.535178 -84.379308)
		(end 0.15113 -83.693)
		(width 0.1397)
		(layer "F.Cu")
		(net "SD_LATCH_RELEASE")
	)
	(segment
		(start 144.960086 -59.539886)
		(end 144.240758 -60.259214)
		(width 0.1397)
		(layer "F.Cu")
		(net "SD_LATCH_RELEASE")
	)
	(segment
		(start 25.215088 -81.454498)
		(end 28.84551 -77.824076)
		(width 0.1397)
		(layer "F.Cu")
		(net "SD_LATCH_RELEASE")
	)
	(segment
		(start 0.15113 -83.693)
		(end 0.993394 -83.693)
		(width 0.1397)
		(layer "F.Cu")
		(net "SD_LATCH_RELEASE")
	)
	(segment
		(start 3.23215 -81.454244)
		(end 24.110442 -81.454244)
		(width 0.1397)
		(layer "F.Cu")
		(net "SD_LATCH_RELEASE")
	)
	(via
		(at 101.996494 -77.824076)
		(size 0.7112)
		(drill 0.3556)
		(layers "F.Cu" "B.Cu")
		(net "SD_LATCH_RELEASE")
	)
	(segment
		(start 25.399238 -81.898998)
		(end 28.92171 -78.376526)
		(width 0.1397)
		(layer "F.Cu")
		(net "FCB_HW_REV")
	)
	(segment
		(start 23.926546 -81.898998)
		(end 25.399238 -81.898998)
		(width 0.1397)
		(layer "F.Cu")
		(net "FCB_HW_REV")
	)
	(segment
		(start -6.99897 -85.649308)
		(end -3.480308 -85.649308)
		(width 0.1397)
		(layer "F.Cu")
		(net "FCB_HW_REV")
	)
	(segment
		(start 136.614154 -60.703714)
		(end 118.941342 -78.376526)
		(width 0.1397)
		(layer "F.Cu")
		(net "FCB_HW_REV")
	)
	(segment
		(start 144.960086 -56.999886)
		(end 144.960086 -57.577736)
		(width 0.1397)
		(layer "F.Cu")
		(net "FCB_HW_REV")
	)
	(segment
		(start 145.417286 -60.703714)
		(end 136.614154 -60.703714)
		(width 0.1397)
		(layer "F.Cu")
		(net "FCB_HW_REV")
	)
	(segment
		(start 145.880836 -60.240164)
		(end 145.417286 -60.703714)
		(width 0.1397)
		(layer "F.Cu")
		(net "FCB_HW_REV")
	)
	(segment
		(start 28.92171 -78.376526)
		(end 111.609378 -78.376526)
		(width 0.1397)
		(layer "F.Cu")
		(net "FCB_HW_REV")
	)
	(segment
		(start 144.960086 -57.577736)
		(end 145.880836 -58.498486)
		(width 0.1397)
		(layer "F.Cu")
		(net "FCB_HW_REV")
	)
	(segment
		(start 145.880836 -58.498486)
		(end 145.880836 -60.240164)
		(width 0.1397)
		(layer "F.Cu")
		(net "FCB_HW_REV")
	)
	(segment
		(start 118.941342 -78.376526)
		(end 111.609378 -78.376526)
		(width 0.1397)
		(layer "F.Cu")
		(net "FCB_HW_REV")
	)
	(segment
		(start -0.362966 -84.836)
		(end 0.272034 -84.201)
		(width 0.1397)
		(layer "F.Cu")
		(net "FCB_HW_REV")
	)
	(segment
		(start 3.4163 -81.898744)
		(end 23.926292 -81.898744)
		(width 0.1397)
		(layer "F.Cu")
		(net "FCB_HW_REV")
	)
	(segment
		(start 0.272034 -84.201)
		(end 1.114044 -84.201)
		(width 0.1397)
		(layer "F.Cu")
		(net "FCB_HW_REV")
	)
	(segment
		(start -2.667 -84.836)
		(end -0.362966 -84.836)
		(width 0.1397)
		(layer "F.Cu")
		(net "FCB_HW_REV")
	)
	(segment
		(start -3.480308 -85.649308)
		(end -2.667 -84.836)
		(width 0.1397)
		(layer "F.Cu")
		(net "FCB_HW_REV")
	)
	(segment
		(start 23.926292 -81.898744)
		(end 23.926546 -81.898998)
		(width 0.1397)
		(layer "F.Cu")
		(net "FCB_HW_REV")
	)
	(segment
		(start 1.114044 -84.201)
		(end 3.4163 -81.898744)
		(width 0.1397)
		(layer "F.Cu")
		(net "FCB_HW_REV")
	)
	(via
		(at 111.609378 -78.376526)
		(size 0.7112)
		(drill 0.3556)
		(layers "F.Cu" "B.Cu")
		(net "FCB_HW_REV")
	)
	(segment
		(start 25.583642 -82.343498)
		(end 25.844246 -82.082894)
		(width 0.1397)
		(layer "F.Cu")
		(net "TRAY_ID")
	)
	(segment
		(start 25.844246 -82.082894)
		(end 25.844246 -82.08264)
		(width 0.1397)
		(layer "F.Cu")
		(net "TRAY_ID")
	)
	(segment
		(start 145.734786 -61.148214)
		(end 145.601436 -61.148214)
		(width 0.1397)
		(layer "F.Cu")
		(net "TRAY_ID")
	)
	(segment
		(start 146.05 -55.5498)
		(end 146.05 -58.039)
		(width 0.1397)
		(layer "F.Cu")
		(net "TRAY_ID")
	)
	(segment
		(start 119.017542 -78.928976)
		(end 78.99146 -78.928976)
		(width 0.1397)
		(layer "F.Cu")
		(net "TRAY_ID")
	)
	(segment
		(start -1.391158 -86.493096)
		(end 0.392938 -84.709)
		(width 0.1397)
		(layer "F.Cu")
		(net "TRAY_ID")
	)
	(segment
		(start 3.600704 -82.343244)
		(end 23.742142 -82.343244)
		(width 0.1397)
		(layer "F.Cu")
		(net "TRAY_ID")
	)
	(segment
		(start 145.23339 -61.148468)
		(end 145.233136 -61.148214)
		(width 0.1397)
		(layer "F.Cu")
		(net "TRAY_ID")
	)
	(segment
		(start 144.960086 -54.459886)
		(end 146.05 -55.5498)
		(width 0.1397)
		(layer "F.Cu")
		(net "TRAY_ID")
	)
	(segment
		(start 145.233136 -61.148214)
		(end 136.798304 -61.148214)
		(width 0.1397)
		(layer "F.Cu")
		(net "TRAY_ID")
	)
	(segment
		(start 146.325336 -60.557664)
		(end 145.734786 -61.148214)
		(width 0.1397)
		(layer "F.Cu")
		(net "TRAY_ID")
	)
	(segment
		(start 23.742396 -82.343498)
		(end 25.583642 -82.343498)
		(width 0.1397)
		(layer "F.Cu")
		(net "TRAY_ID")
	)
	(segment
		(start 136.798304 -61.148214)
		(end 119.017542 -78.928976)
		(width 0.1397)
		(layer "F.Cu")
		(net "TRAY_ID")
	)
	(segment
		(start 0.392938 -84.709)
		(end 1.234948 -84.709)
		(width 0.1397)
		(layer "F.Cu")
		(net "TRAY_ID")
	)
	(segment
		(start -3.510788 -86.493096)
		(end -1.391158 -86.493096)
		(width 0.1397)
		(layer "F.Cu")
		(net "TRAY_ID")
	)
	(segment
		(start 23.742142 -82.343244)
		(end 23.742396 -82.343498)
		(width 0.1397)
		(layer "F.Cu")
		(net "TRAY_ID")
	)
	(segment
		(start -3.937 -86.919308)
		(end -3.510788 -86.493096)
		(width 0.1397)
		(layer "F.Cu")
		(net "TRAY_ID")
	)
	(segment
		(start 146.325336 -58.314336)
		(end 146.325336 -60.557664)
		(width 0.1397)
		(layer "F.Cu")
		(net "TRAY_ID")
	)
	(segment
		(start 1.234948 -84.709)
		(end 3.600704 -82.343244)
		(width 0.1397)
		(layer "F.Cu")
		(net "TRAY_ID")
	)
	(segment
		(start 146.05 -58.039)
		(end 146.325336 -58.314336)
		(width 0.1397)
		(layer "F.Cu")
		(net "TRAY_ID")
	)
	(segment
		(start -6.99897 -86.919308)
		(end -3.937 -86.919308)
		(width 0.1397)
		(layer "F.Cu")
		(net "TRAY_ID")
	)
	(segment
		(start 25.844246 -82.08264)
		(end 28.99791 -78.928976)
		(width 0.1397)
		(layer "F.Cu")
		(net "TRAY_ID")
	)
	(segment
		(start 145.601436 -61.148214)
		(end 145.601182 -61.148468)
		(width 0.1397)
		(layer "F.Cu")
		(net "TRAY_ID")
	)
	(segment
		(start 28.99791 -78.928976)
		(end 78.99146 -78.928976)
		(width 0.1397)
		(layer "F.Cu")
		(net "TRAY_ID")
	)
	(segment
		(start 145.601182 -61.148468)
		(end 145.23339 -61.148468)
		(width 0.1397)
		(layer "F.Cu")
		(net "TRAY_ID")
	)
	(via
		(at 78.99146 -78.928976)
		(size 0.7112)
		(drill 0.3556)
		(layers "F.Cu" "B.Cu")
		(net "TRAY_ID")
	)
	(segment
		(start 143.51 -59.055)
		(end 143.51 -53.369972)
		(width 0.1397)
		(layer "F.Cu")
		(net "PEER_TRAY_PRESENT")
	)
	(segment
		(start 28.76931 -77.271626)
		(end 34.306002 -77.271626)
		(width 0.1397)
		(layer "F.Cu")
		(net "PEER_TRAY_PRESENT")
	)
	(segment
		(start 24.294592 -81.009744)
		(end 24.294846 -81.009998)
		(width 0.1397)
		(layer "F.Cu")
		(net "PEER_TRAY_PRESENT")
	)
	(segment
		(start 34.306002 -77.271626)
		(end 118.788942 -77.271626)
		(width 0.1397)
		(layer "F.Cu")
		(net "PEER_TRAY_PRESENT")
	)
	(segment
		(start 0.994918 -83.041744)
		(end 3.026918 -81.009744)
		(width 0.1397)
		(layer "F.Cu")
		(net "PEER_TRAY_PRESENT")
	)
	(segment
		(start 137.031222 -59.814714)
		(end 137.031476 -59.81446)
		(width 0.1397)
		(layer "F.Cu")
		(net "PEER_TRAY_PRESENT")
	)
	(segment
		(start 3.026918 -81.009744)
		(end 24.294592 -81.009744)
		(width 0.1397)
		(layer "F.Cu")
		(net "PEER_TRAY_PRESENT")
	)
	(segment
		(start 137.031476 -59.81446)
		(end 142.75054 -59.81446)
		(width 0.1397)
		(layer "F.Cu")
		(net "PEER_TRAY_PRESENT")
	)
	(segment
		(start 24.294846 -81.009998)
		(end 25.030938 -81.009998)
		(width 0.1397)
		(layer "F.Cu")
		(net "PEER_TRAY_PRESENT")
	)
	(segment
		(start 142.75054 -59.81446)
		(end 143.51 -59.055)
		(width 0.1397)
		(layer "F.Cu")
		(net "PEER_TRAY_PRESENT")
	)
	(segment
		(start 0.863092 -83.041744)
		(end 0.994918 -83.041744)
		(width 0.1397)
		(layer "F.Cu")
		(net "PEER_TRAY_PRESENT")
	)
	(segment
		(start 136.245854 -59.814714)
		(end 137.031222 -59.814714)
		(width 0.1397)
		(layer "F.Cu")
		(net "PEER_TRAY_PRESENT")
	)
	(segment
		(start 25.030938 -81.009998)
		(end 28.76931 -77.271626)
		(width 0.1397)
		(layer "F.Cu")
		(net "PEER_TRAY_PRESENT")
	)
	(segment
		(start 143.51 -53.369972)
		(end 144.960086 -51.919886)
		(width 0.1397)
		(layer "F.Cu")
		(net "PEER_TRAY_PRESENT")
	)
	(segment
		(start 118.788942 -77.271626)
		(end 136.245854 -59.814714)
		(width 0.1397)
		(layer "F.Cu")
		(net "PEER_TRAY_PRESENT")
	)
	(via
		(at 0.863092 -83.041744)
		(size 0.7112)
		(drill 0.4064)
		(layers "F.Cu" "B.Cu")
		(net "PEER_TRAY_PRESENT")
	)
	(via
		(at 34.306002 -77.271626)
		(size 0.7112)
		(drill 0.3556)
		(layers "F.Cu" "B.Cu")
		(net "PEER_TRAY_PRESENT")
	)
	(segment
		(start -3.710686 -81.153)
		(end -1.761744 -81.153)
		(width 0.1397)
		(layer "B.Cu")
		(net "PEER_TRAY_PRESENT")
	)
	(segment
		(start -4.294378 -80.569308)
		(end -3.710686 -81.153)
		(width 0.1397)
		(layer "B.Cu")
		(net "PEER_TRAY_PRESENT")
	)
	(segment
		(start -1.761744 -81.153)
		(end 0.127 -83.041744)
		(width 0.1397)
		(layer "B.Cu")
		(net "PEER_TRAY_PRESENT")
	)
	(segment
		(start -6.61797 -80.569308)
		(end -4.294378 -80.569308)
		(width 0.1397)
		(layer "B.Cu")
		(net "PEER_TRAY_PRESENT")
	)
	(segment
		(start 0.127 -83.041744)
		(end 0.863092 -83.041744)
		(width 0.1397)
		(layer "B.Cu")
		(net "PEER_TRAY_PRESENT")
	)
	(segment
		(start 8.523732 -95.029528)
		(end 9.684512 -95.029528)
		(width 0.1397)
		(layer "F.Cu")
		(net "I2C_C_SDA")
	)
	(segment
		(start 7.677658 -96.266762)
		(end 7.158228 -96.266762)
		(width 0.1397)
		(layer "F.Cu")
		(net "I2C_C_SDA")
	)
	(segment
		(start 9.684512 -95.029528)
		(end 10.102596 -94.611444)
		(width 0.1397)
		(layer "F.Cu")
		(net "I2C_C_SDA")
	)
	(segment
		(start 8.523732 -95.420688)
		(end 7.677658 -96.266762)
		(width 0.1397)
		(layer "F.Cu")
		(net "I2C_C_SDA")
	)
	(segment
		(start 11.24458 -94.671896)
		(end 10.962386 -94.95409)
		(width 0.1397)
		(layer "F.Cu")
		(net "I2C_C_SDA")
	)
	(segment
		(start 16.788638 -94.990666)
		(end 16.469868 -94.671896)
		(width 0.1397)
		(layer "F.Cu")
		(net "I2C_C_SDA")
	)
	(segment
		(start 10.61974 -94.611444)
		(end 10.962386 -94.95409)
		(width 0.1397)
		(layer "F.Cu")
		(net "I2C_C_SDA")
	)
	(segment
		(start 10.102596 -94.611444)
		(end 10.61974 -94.611444)
		(width 0.1397)
		(layer "F.Cu")
		(net "I2C_C_SDA")
	)
	(segment
		(start 16.469868 -94.671896)
		(end 11.24458 -94.671896)
		(width 0.1397)
		(layer "F.Cu")
		(net "I2C_C_SDA")
	)
	(segment
		(start 8.523732 -95.029528)
		(end 8.523732 -95.420688)
		(width 0.1397)
		(layer "F.Cu")
		(net "I2C_C_SDA")
	)
	(via
		(at 7.158228 -96.266762)
		(size 0.7112)
		(drill 0.3556)
		(layers "F.Cu" "B.Cu")
		(net "I2C_C_SDA")
	)
	(segment
		(start 138.049254 -66.79438)
		(end 137.795 -67.048634)
		(width 0.1397)
		(layer "F.Cu")
		(net "I2C_C_BUF_SCL_CONN")
	)
	(segment
		(start 154.1907 -58.6105)
		(end 154.1907 -67.9323)
		(width 0.1397)
		(layer "F.Cu")
		(net "I2C_C_BUF_SCL_CONN")
	)
	(segment
		(start 154.1907 -67.9323)
		(end 153.3017 -68.8213)
		(width 0.1397)
		(layer "F.Cu")
		(net "I2C_C_BUF_SCL_CONN")
	)
	(segment
		(start 136.596882 -67.048634)
		(end 137.795 -67.048634)
		(width 0.1397)
		(layer "F.Cu")
		(net "I2C_C_BUF_SCL_CONN")
	)
	(segment
		(start 139.81938 -66.79438)
		(end 139.297918 -66.79438)
		(width 0.1397)
		(layer "F.Cu")
		(net "I2C_C_BUF_SCL_CONN")
	)
	(segment
		(start 141.8463 -68.8213)
		(end 139.81938 -66.79438)
		(width 0.1397)
		(layer "F.Cu")
		(net "I2C_C_BUF_SCL_CONN")
	)
	(segment
		(start 139.297918 -66.79438)
		(end 138.049254 -66.79438)
		(width 0.1397)
		(layer "F.Cu")
		(net "I2C_C_BUF_SCL_CONN")
	)
	(segment
		(start 153.3017 -68.8213)
		(end 141.8463 -68.8213)
		(width 0.1397)
		(layer "F.Cu")
		(net "I2C_C_BUF_SCL_CONN")
	)
	(segment
		(start 152.580086 -56.999886)
		(end 154.1907 -58.6105)
		(width 0.1397)
		(layer "F.Cu")
		(net "I2C_C_BUF_SCL_CONN")
	)
	(via
		(at 139.297918 -66.79438)
		(size 0.7112)
		(drill 0.3556)
		(layers "F.Cu" "B.Cu")
		(net "I2C_C_BUF_SCL_CONN")
	)
	(segment
		(start 136.847326 -59.36996)
		(end 136.847072 -59.370214)
		(width 0.1397)
		(layer "F.Cu")
		(net "PEER_1A&2A_HB")
	)
	(segment
		(start 2.842768 -80.565244)
		(end 24.478742 -80.565244)
		(width 0.1397)
		(layer "F.Cu")
		(net "PEER_1A&2A_HB")
	)
	(segment
		(start 24.478742 -80.565244)
		(end 24.478996 -80.565498)
		(width 0.1397)
		(layer "F.Cu")
		(net "PEER_1A&2A_HB")
	)
	(segment
		(start 142.17904 -59.36996)
		(end 136.847326 -59.36996)
		(width 0.1397)
		(layer "F.Cu")
		(net "PEER_1A&2A_HB")
	)
	(segment
		(start -2.79908 -82.26552)
		(end 1.142492 -82.26552)
		(width 0.1397)
		(layer "F.Cu")
		(net "PEER_1A&2A_HB")
	)
	(segment
		(start 28.69311 -76.719176)
		(end 49.857406 -76.719176)
		(width 0.1397)
		(layer "F.Cu")
		(net "PEER_1A&2A_HB")
	)
	(segment
		(start 24.846788 -80.565498)
		(end 28.69311 -76.719176)
		(width 0.1397)
		(layer "F.Cu")
		(net "PEER_1A&2A_HB")
	)
	(segment
		(start 24.478996 -80.565498)
		(end 24.846788 -80.565498)
		(width 0.1397)
		(layer "F.Cu")
		(net "PEER_1A&2A_HB")
	)
	(segment
		(start 118.712742 -76.719176)
		(end 49.857406 -76.719176)
		(width 0.1397)
		(layer "F.Cu")
		(net "PEER_1A&2A_HB")
	)
	(segment
		(start 136.061704 -59.370214)
		(end 118.712742 -76.719176)
		(width 0.1397)
		(layer "F.Cu")
		(net "PEER_1A&2A_HB")
	)
	(segment
		(start 142.621 -58.928)
		(end 142.17904 -59.36996)
		(width 0.1397)
		(layer "F.Cu")
		(net "PEER_1A&2A_HB")
	)
	(segment
		(start 1.142492 -82.26552)
		(end 2.842768 -80.565244)
		(width 0.1397)
		(layer "F.Cu")
		(net "PEER_1A&2A_HB")
	)
	(segment
		(start -3.225292 -81.839308)
		(end -2.79908 -82.26552)
		(width 0.1397)
		(layer "F.Cu")
		(net "PEER_1A&2A_HB")
	)
	(segment
		(start 136.847072 -59.370214)
		(end 136.061704 -59.370214)
		(width 0.1397)
		(layer "F.Cu")
		(net "PEER_1A&2A_HB")
	)
	(segment
		(start -6.99897 -81.839308)
		(end -3.225292 -81.839308)
		(width 0.1397)
		(layer "F.Cu")
		(net "PEER_1A&2A_HB")
	)
	(via
		(at 142.621 -58.928)
		(size 0.7112)
		(drill 0.4064)
		(layers "F.Cu" "B.Cu")
		(net "PEER_1A&2A_HB")
	)
	(via
		(at 49.857406 -76.719176)
		(size 0.7112)
		(drill 0.3556)
		(layers "F.Cu" "B.Cu")
		(net "PEER_1A&2A_HB")
	)
	(segment
		(start 146.524472 -60.5155)
		(end 147.500086 -59.539886)
		(width 0.1397)
		(layer "B.Cu")
		(net "PEER_1A&2A_HB")
	)
	(segment
		(start 142.621 -59.309)
		(end 143.8275 -60.5155)
		(width 0.1397)
		(layer "B.Cu")
		(net "PEER_1A&2A_HB")
	)
	(segment
		(start 142.621 -58.928)
		(end 142.621 -59.309)
		(width 0.1397)
		(layer "B.Cu")
		(net "PEER_1A&2A_HB")
	)
	(segment
		(start 143.8275 -60.5155)
		(end 146.524472 -60.5155)
		(width 0.1397)
		(layer "B.Cu")
		(net "PEER_1A&2A_HB")
	)
	(segment
		(start 16.776192 -93.84538)
		(end 16.518636 -94.102936)
		(width 0.1397)
		(layer "F.Cu")
		(net "I2C_C_SCL")
	)
	(segment
		(start 8.523732 -93.317568)
		(end 8.523732 -93.708728)
		(width 0.1397)
		(layer "F.Cu")
		(net "I2C_C_SCL")
	)
	(segment
		(start 10.940288 -93.801438)
		(end 10.650982 -94.090744)
		(width 0.1397)
		(layer "F.Cu")
		(net "I2C_C_SCL")
	)
	(segment
		(start 7.677658 -92.471494)
		(end 8.523732 -93.317568)
		(width 0.1397)
		(layer "F.Cu")
		(net "I2C_C_SCL")
	)
	(segment
		(start 7.158228 -92.471494)
		(end 7.677658 -92.471494)
		(width 0.1397)
		(layer "F.Cu")
		(net "I2C_C_SCL")
	)
	(segment
		(start 10.650982 -94.090744)
		(end 10.061448 -94.090744)
		(width 0.1397)
		(layer "F.Cu")
		(net "I2C_C_SCL")
	)
	(segment
		(start 9.679686 -93.708982)
		(end 8.523986 -93.708982)
		(width 0.1397)
		(layer "F.Cu")
		(net "I2C_C_SCL")
	)
	(segment
		(start 16.518636 -94.102936)
		(end 11.241786 -94.102936)
		(width 0.1397)
		(layer "F.Cu")
		(net "I2C_C_SCL")
	)
	(segment
		(start 11.241786 -94.102936)
		(end 10.940288 -93.801438)
		(width 0.1397)
		(layer "F.Cu")
		(net "I2C_C_SCL")
	)
	(segment
		(start 10.061448 -94.090744)
		(end 9.679686 -93.708982)
		(width 0.1397)
		(layer "F.Cu")
		(net "I2C_C_SCL")
	)
	(segment
		(start 8.523986 -93.708982)
		(end 8.523732 -93.708728)
		(width 0.1397)
		(layer "F.Cu")
		(net "I2C_C_SCL")
	)
	(via
		(at 7.158228 -92.471494)
		(size 0.7112)
		(drill 0.3556)
		(layers "F.Cu" "B.Cu")
		(net "I2C_C_SCL")
	)
	(segment
		(start 136.596882 -68.318634)
		(end 137.795 -68.318634)
		(width 0.1397)
		(layer "F.Cu")
		(net "I2C_C_BUF_SDA_CONN")
	)
	(segment
		(start 141.605 -69.342)
		(end 153.543 -69.342)
		(width 0.1397)
		(layer "F.Cu")
		(net "I2C_C_BUF_SDA_CONN")
	)
	(segment
		(start 153.543 -69.342)
		(end 154.7114 -68.1736)
		(width 0.1397)
		(layer "F.Cu")
		(net "I2C_C_BUF_SDA_CONN")
	)
	(segment
		(start 140.78458 -68.52158)
		(end 141.605 -69.342)
		(width 0.1397)
		(layer "F.Cu")
		(net "I2C_C_BUF_SDA_CONN")
	)
	(segment
		(start 139.297918 -68.52158)
		(end 140.78458 -68.52158)
		(width 0.1397)
		(layer "F.Cu")
		(net "I2C_C_BUF_SDA_CONN")
	)
	(segment
		(start 137.997946 -68.52158)
		(end 137.795 -68.318634)
		(width 0.1397)
		(layer "F.Cu")
		(net "I2C_C_BUF_SDA_CONN")
	)
	(segment
		(start 154.7114 -54.0512)
		(end 152.580086 -51.919886)
		(width 0.1397)
		(layer "F.Cu")
		(net "I2C_C_BUF_SDA_CONN")
	)
	(segment
		(start 154.7114 -68.1736)
		(end 154.7114 -54.0512)
		(width 0.1397)
		(layer "F.Cu")
		(net "I2C_C_BUF_SDA_CONN")
	)
	(segment
		(start 139.297918 -68.52158)
		(end 137.997946 -68.52158)
		(width 0.1397)
		(layer "F.Cu")
		(net "I2C_C_BUF_SDA_CONN")
	)
	(via
		(at 139.297918 -68.52158)
		(size 0.7112)
		(drill 0.3556)
		(layers "F.Cu" "B.Cu")
		(net "I2C_C_BUF_SDA_CONN")
	)
	(segment
		(start 141.35354 -58.92546)
		(end 135.877808 -58.92546)
		(width 0.1397)
		(layer "F.Cu")
		(net "PEER_1B&2B_HB")
	)
	(segment
		(start 118.636542 -76.166726)
		(end 117.667786 -76.166726)
		(width 0.1397)
		(layer "F.Cu")
		(net "PEER_1B&2B_HB")
	)
	(segment
		(start 24.662638 -80.120744)
		(end 28.616656 -76.166726)
		(width 0.1397)
		(layer "F.Cu")
		(net "PEER_1B&2B_HB")
	)
	(segment
		(start -2.61493 -81.82102)
		(end 0.958342 -81.82102)
		(width 0.1397)
		(layer "F.Cu")
		(net "PEER_1B&2B_HB")
	)
	(segment
		(start 28.616656 -76.166726)
		(end 117.667786 -76.166726)
		(width 0.1397)
		(layer "F.Cu")
		(net "PEER_1B&2B_HB")
	)
	(segment
		(start 135.877808 -58.92546)
		(end 118.636542 -76.166726)
		(width 0.1397)
		(layer "F.Cu")
		(net "PEER_1B&2B_HB")
	)
	(segment
		(start -6.99897 -80.569308)
		(end -3.866642 -80.569308)
		(width 0.1397)
		(layer "F.Cu")
		(net "PEER_1B&2B_HB")
	)
	(segment
		(start 141.478 -58.801)
		(end 141.35354 -58.92546)
		(width 0.1397)
		(layer "F.Cu")
		(net "PEER_1B&2B_HB")
	)
	(segment
		(start 2.658618 -80.120744)
		(end 24.662638 -80.120744)
		(width 0.1397)
		(layer "F.Cu")
		(net "PEER_1B&2B_HB")
	)
	(segment
		(start 0.958342 -81.82102)
		(end 2.658618 -80.120744)
		(width 0.1397)
		(layer "F.Cu")
		(net "PEER_1B&2B_HB")
	)
	(segment
		(start -3.866642 -80.569308)
		(end -2.61493 -81.82102)
		(width 0.1397)
		(layer "F.Cu")
		(net "PEER_1B&2B_HB")
	)
	(via
		(at 117.667786 -76.166726)
		(size 0.7112)
		(drill 0.3556)
		(layers "F.Cu" "B.Cu")
		(net "PEER_1B&2B_HB")
	)
	(via
		(at 141.478 -58.801)
		(size 0.7112)
		(drill 0.4064)
		(layers "F.Cu" "B.Cu")
		(net "PEER_1B&2B_HB")
	)
	(segment
		(start 141.478 -58.801)
		(end 143.637 -60.96)
		(width 0.1397)
		(layer "B.Cu")
		(net "PEER_1B&2B_HB")
	)
	(segment
		(start 143.637 -60.96)
		(end 146.3802 -60.96)
		(width 0.1397)
		(layer "B.Cu")
		(net "PEER_1B&2B_HB")
	)
	(segment
		(start 146.3802 -60.96)
		(end 147.500086 -62.079886)
		(width 0.1397)
		(layer "B.Cu")
		(net "PEER_1B&2B_HB")
	)
	(segment
		(start 150.368 -64.262)
		(end 143.383 -64.262)
		(width 0.1397)
		(layer "F.Cu")
		(net "SELF_1A&2A_HB")
	)
	(segment
		(start 4.601718 -83.676744)
		(end 23.189692 -83.676744)
		(width 0.1397)
		(layer "F.Cu")
		(net "SELF_1A&2A_HB")
	)
	(segment
		(start 29.226764 -80.586326)
		(end 67.22872 -80.586326)
		(width 0.1397)
		(layer "F.Cu")
		(net "SELF_1A&2A_HB")
	)
	(segment
		(start 148.6662 -58.166)
		(end 150.241 -58.166)
		(width 0.1397)
		(layer "F.Cu")
		(net "SELF_1A&2A_HB")
	)
	(segment
		(start 119.246142 -80.586326)
		(end 67.22872 -80.586326)
		(width 0.1397)
		(layer "F.Cu")
		(net "SELF_1A&2A_HB")
	)
	(segment
		(start -6.99897 -89.459308)
		(end -4.064 -89.459308)
		(width 0.1397)
		(layer "F.Cu")
		(net "SELF_1A&2A_HB")
	)
	(segment
		(start 151.0665 -63.5635)
		(end 150.368 -64.262)
		(width 0.1397)
		(layer "F.Cu")
		(net "SELF_1A&2A_HB")
	)
	(segment
		(start 151.0665 -58.9915)
		(end 151.0665 -63.5635)
		(width 0.1397)
		(layer "F.Cu")
		(net "SELF_1A&2A_HB")
	)
	(segment
		(start 2.553462 -85.725)
		(end 4.601718 -83.676744)
		(width 0.1397)
		(layer "F.Cu")
		(net "SELF_1A&2A_HB")
	)
	(segment
		(start 143.383 -64.262)
		(end 141.602714 -62.481714)
		(width 0.1397)
		(layer "F.Cu")
		(net "SELF_1A&2A_HB")
	)
	(segment
		(start 150.241 -58.166)
		(end 151.0665 -58.9915)
		(width 0.1397)
		(layer "F.Cu")
		(net "SELF_1A&2A_HB")
	)
	(segment
		(start -1.986788 -87.382096)
		(end -1.022096 -87.382096)
		(width 0.1397)
		(layer "F.Cu")
		(net "SELF_1A&2A_HB")
	)
	(segment
		(start -4.064 -89.459308)
		(end -1.986788 -87.382096)
		(width 0.1397)
		(layer "F.Cu")
		(net "SELF_1A&2A_HB")
	)
	(segment
		(start 23.189946 -83.676998)
		(end 26.136092 -83.676998)
		(width 0.1397)
		(layer "F.Cu")
		(net "SELF_1A&2A_HB")
	)
	(segment
		(start 141.602714 -62.481714)
		(end 137.350754 -62.481714)
		(width 0.1397)
		(layer "F.Cu")
		(net "SELF_1A&2A_HB")
	)
	(segment
		(start 147.500086 -56.999886)
		(end 148.6662 -58.166)
		(width 0.1397)
		(layer "F.Cu")
		(net "SELF_1A&2A_HB")
	)
	(segment
		(start -1.022096 -87.382096)
		(end 0.635 -85.725)
		(width 0.1397)
		(layer "F.Cu")
		(net "SELF_1A&2A_HB")
	)
	(segment
		(start 26.136092 -83.676998)
		(end 29.226764 -80.586326)
		(width 0.1397)
		(layer "F.Cu")
		(net "SELF_1A&2A_HB")
	)
	(segment
		(start 0.635 -85.725)
		(end 2.553462 -85.725)
		(width 0.1397)
		(layer "F.Cu")
		(net "SELF_1A&2A_HB")
	)
	(segment
		(start 137.350754 -62.481714)
		(end 119.246142 -80.586326)
		(width 0.1397)
		(layer "F.Cu")
		(net "SELF_1A&2A_HB")
	)
	(segment
		(start 23.189692 -83.676744)
		(end 23.189946 -83.676998)
		(width 0.1397)
		(layer "F.Cu")
		(net "SELF_1A&2A_HB")
	)
	(via
		(at 67.22872 -80.586326)
		(size 0.7112)
		(drill 0.3556)
		(layers "F.Cu" "B.Cu")
		(net "SELF_1A&2A_HB")
	)
	(segment
		(start 141.786864 -62.037214)
		(end 137.166604 -62.037214)
		(width 0.1397)
		(layer "F.Cu")
		(net "SELF_1B&2B_HB")
	)
	(segment
		(start 29.150564 -80.033876)
		(end 58.093864 -80.033876)
		(width 0.1397)
		(layer "F.Cu")
		(net "SELF_1B&2B_HB")
	)
	(segment
		(start 4.417314 -83.232244)
		(end 23.373842 -83.232244)
		(width 0.1397)
		(layer "F.Cu")
		(net "SELF_1B&2B_HB")
	)
	(segment
		(start 148.2725 -63.8175)
		(end 143.56715 -63.8175)
		(width 0.1397)
		(layer "F.Cu")
		(net "SELF_1B&2B_HB")
	)
	(segment
		(start 119.169942 -80.033876)
		(end 58.093864 -80.033876)
		(width 0.1397)
		(layer "F.Cu")
		(net "SELF_1B&2B_HB")
	)
	(segment
		(start -2.939288 -86.937596)
		(end -1.206754 -86.937596)
		(width 0.1397)
		(layer "F.Cu")
		(net "SELF_1B&2B_HB")
	)
	(segment
		(start 137.166604 -62.037214)
		(end 119.169942 -80.033876)
		(width 0.1397)
		(layer "F.Cu")
		(net "SELF_1B&2B_HB")
	)
	(segment
		(start -1.206754 -86.937596)
		(end 0.513842 -85.217)
		(width 0.1397)
		(layer "F.Cu")
		(net "SELF_1B&2B_HB")
	)
	(segment
		(start 0.513842 -85.217)
		(end 2.432558 -85.217)
		(width 0.1397)
		(layer "F.Cu")
		(net "SELF_1B&2B_HB")
	)
	(segment
		(start 25.951942 -83.232498)
		(end 29.150564 -80.033876)
		(width 0.1397)
		(layer "F.Cu")
		(net "SELF_1B&2B_HB")
	)
	(segment
		(start 2.432558 -85.217)
		(end 4.417314 -83.232244)
		(width 0.1397)
		(layer "F.Cu")
		(net "SELF_1B&2B_HB")
	)
	(segment
		(start -6.99897 -88.189308)
		(end -4.191 -88.189308)
		(width 0.1397)
		(layer "F.Cu")
		(net "SELF_1B&2B_HB")
	)
	(segment
		(start 23.373842 -83.232244)
		(end 23.374096 -83.232498)
		(width 0.1397)
		(layer "F.Cu")
		(net "SELF_1B&2B_HB")
	)
	(segment
		(start -4.191 -88.189308)
		(end -2.939288 -86.937596)
		(width 0.1397)
		(layer "F.Cu")
		(net "SELF_1B&2B_HB")
	)
	(segment
		(start 23.374096 -83.232498)
		(end 25.951942 -83.232498)
		(width 0.1397)
		(layer "F.Cu")
		(net "SELF_1B&2B_HB")
	)
	(segment
		(start 148.844 -60.735972)
		(end 148.844 -63.246)
		(width 0.1397)
		(layer "F.Cu")
		(net "SELF_1B&2B_HB")
	)
	(segment
		(start 148.844 -63.246)
		(end 148.2725 -63.8175)
		(width 0.1397)
		(layer "F.Cu")
		(net "SELF_1B&2B_HB")
	)
	(segment
		(start 150.040086 -59.539886)
		(end 148.844 -60.735972)
		(width 0.1397)
		(layer "F.Cu")
		(net "SELF_1B&2B_HB")
	)
	(segment
		(start 143.56715 -63.8175)
		(end 141.786864 -62.037214)
		(width 0.1397)
		(layer "F.Cu")
		(net "SELF_1B&2B_HB")
	)
	(via
		(at 58.093864 -80.033876)
		(size 0.7112)
		(drill 0.3556)
		(layers "F.Cu" "B.Cu")
		(net "SELF_1B&2B_HB")
	)
	(via
		(at 158.724092 -101.837744)
		(size 0.7112)
		(drill 0.3556)
		(layers "F.Cu" "B.Cu")
		(net "DETECTOR_C")
	)
	(via
		(at 158.139892 -84.260944)
		(size 0.7112)
		(drill 0.3556)
		(layers "F.Cu" "B.Cu")
		(net "EMITTER_K")
	)
	(segment
		(start 136.635744 -81.813908)
		(end 135.556244 -81.813908)
		(width 0.1397)
		(layer "F.Cu")
		(net "TRAY_PRESENT_OUT_NET_B")
	)
	(segment
		(start 135.359394 -81.617058)
		(end 135.359394 -80.226408)
		(width 0.1397)
		(layer "F.Cu")
		(net "TRAY_PRESENT_OUT_NET_B")
	)
	(segment
		(start 135.556244 -81.813908)
		(end 135.359394 -81.617058)
		(width 0.1397)
		(layer "F.Cu")
		(net "TRAY_PRESENT_OUT_NET_B")
	)
	(via
		(at 136.635744 -81.813908)
		(size 0.7112)
		(drill 0.3556)
		(layers "F.Cu" "B.Cu")
		(net "TRAY_PRESENT_OUT_NET_B")
	)
	(segment
		(start 150.040086 -42.579798)
		(end 150.040086 -43.659806)
		(width 0.508)
		(layer "F.Cu")
		(net "P12V")
	)
	(segment
		(start 150.040086 -43.659806)
		(end 151.120094 -43.659806)
		(width 0.508)
		(layer "F.Cu")
		(net "P12V")
	)
	(segment
		(start 144.960086 -48.739806)
		(end 146.040094 -48.739806)
		(width 0.508)
		(layer "F.Cu")
		(net "P12V")
	)
	(segment
		(start 146.420078 -43.659806)
		(end 147.500086 -43.659806)
		(width 0.508)
		(layer "F.Cu")
		(net "P12V")
	)
	(segment
		(start 151.500078 -48.739806)
		(end 152.580086 -48.739806)
		(width 0.508)
		(layer "F.Cu")
		(net "P12V")
	)
	(segment
		(start 143.880078 -46.199806)
		(end 144.960086 -46.199806)
		(width 0.508)
		(layer "F.Cu")
		(net "P12V")
	)
	(segment
		(start 144.960086 -43.659806)
		(end 146.040094 -43.659806)
		(width 0.508)
		(layer "F.Cu")
		(net "P12V")
	)
	(segment
		(start 152.580086 -43.659806)
		(end 153.660094 -43.659806)
		(width 0.508)
		(layer "F.Cu")
		(net "P12V")
	)
	(segment
		(start 148.960078 -48.739806)
		(end 150.040086 -48.739806)
		(width 0.508)
		(layer "F.Cu")
		(net "P12V")
	)
	(segment
		(start 152.580086 -46.199806)
		(end 152.580086 -47.279814)
		(width 0.508)
		(layer "F.Cu")
		(net "P12V")
	)
	(segment
		(start 147.500086 -45.119798)
		(end 147.500086 -46.199806)
		(width 0.508)
		(layer "F.Cu")
		(net "P12V")
	)
	(segment
		(start 150.040086 -40.039798)
		(end 150.040086 -41.119806)
		(width 0.508)
		(layer "F.Cu")
		(net "P12V")
	)
	(segment
		(start 150.040086 -48.739806)
		(end 151.120094 -48.739806)
		(width 0.508)
		(layer "F.Cu")
		(net "P12V")
	)
	(segment
		(start 147.500086 -43.659806)
		(end 147.500086 -44.739814)
		(width 0.508)
		(layer "F.Cu")
		(net "P12V")
	)
	(segment
		(start 152.580086 -47.659798)
		(end 152.580086 -48.739806)
		(width 0.508)
		(layer "F.Cu")
		(net "P12V")
	)
	(segment
		(start 144.960086 -46.199806)
		(end 144.960086 -47.279814)
		(width 0.508)
		(layer "F.Cu")
		(net "P12V")
	)
	(segment
		(start 152.580086 -45.119798)
		(end 152.580086 -46.199806)
		(width 0.508)
		(layer "F.Cu")
		(net "P12V")
	)
	(segment
		(start 147.500086 -47.659798)
		(end 147.500086 -48.739806)
		(width 0.508)
		(layer "F.Cu")
		(net "P12V")
	)
	(segment
		(start 144.960086 -42.579798)
		(end 144.960086 -43.659806)
		(width 0.508)
		(layer "F.Cu")
		(net "P12V")
	)
	(segment
		(start 152.580086 -41.119806)
		(end 153.660094 -41.119806)
		(width 0.508)
		(layer "F.Cu")
		(net "P12V")
	)
	(segment
		(start 147.500086 -40.039798)
		(end 147.500086 -41.119806)
		(width 0.508)
		(layer "F.Cu")
		(net "P12V")
	)
	(segment
		(start 150.040086 -48.739806)
		(end 150.040086 -49.819814)
		(width 0.508)
		(layer "F.Cu")
		(net "P12V")
	)
	(segment
		(start 147.500086 -48.739806)
		(end 148.580094 -48.739806)
		(width 0.508)
		(layer "F.Cu")
		(net "P12V")
	)
	(segment
		(start 151.500078 -46.199806)
		(end 152.580086 -46.199806)
		(width 0.508)
		(layer "F.Cu")
		(net "P12V")
	)
	(segment
		(start 152.580086 -41.119806)
		(end 152.580086 -42.199814)
		(width 0.508)
		(layer "F.Cu")
		(net "P12V")
	)
	(segment
		(start 144.960086 -45.119798)
		(end 144.960086 -46.199806)
		(width 0.508)
		(layer "F.Cu")
		(net "P12V")
	)
	(segment
		(start 146.420078 -46.199806)
		(end 147.500086 -46.199806)
		(width 0.508)
		(layer "F.Cu")
		(net "P12V")
	)
	(segment
		(start 147.500086 -48.739806)
		(end 147.500086 -49.819814)
		(width 0.508)
		(layer "F.Cu")
		(net "P12V")
	)
	(segment
		(start 146.420078 -48.739806)
		(end 147.500086 -48.739806)
		(width 0.508)
		(layer "F.Cu")
		(net "P12V")
	)
	(segment
		(start 144.960086 -47.659798)
		(end 144.960086 -48.739806)
		(width 0.508)
		(layer "F.Cu")
		(net "P12V")
	)
	(segment
		(start 143.880078 -41.119806)
		(end 144.960086 -41.119806)
		(width 0.508)
		(layer "F.Cu")
		(net "P12V")
	)
	(segment
		(start 147.500086 -41.119806)
		(end 148.580094 -41.119806)
		(width 0.508)
		(layer "F.Cu")
		(net "P12V")
	)
	(segment
		(start 152.580086 -48.739806)
		(end 152.580086 -49.819814)
		(width 0.508)
		(layer "F.Cu")
		(net "P12V")
	)
	(segment
		(start 147.500086 -42.579798)
		(end 147.500086 -43.659806)
		(width 0.508)
		(layer "F.Cu")
		(net "P12V")
	)
	(segment
		(start 150.040086 -41.119806)
		(end 151.120094 -41.119806)
		(width 0.508)
		(layer "F.Cu")
		(net "P12V")
	)
	(segment
		(start 152.580086 -42.579798)
		(end 152.580086 -43.659806)
		(width 0.508)
		(layer "F.Cu")
		(net "P12V")
	)
	(segment
		(start 151.500078 -41.119806)
		(end 152.580086 -41.119806)
		(width 0.508)
		(layer "F.Cu")
		(net "P12V")
	)
	(segment
		(start 150.040086 -41.119806)
		(end 150.040086 -42.199814)
		(width 0.508)
		(layer "F.Cu")
		(net "P12V")
	)
	(segment
		(start 144.960086 -46.199806)
		(end 146.040094 -46.199806)
		(width 0.508)
		(layer "F.Cu")
		(net "P12V")
	)
	(segment
		(start 152.580086 -40.039798)
		(end 152.580086 -41.119806)
		(width 0.508)
		(layer "F.Cu")
		(net "P12V")
	)
	(segment
		(start 148.960078 -46.199806)
		(end 150.040086 -46.199806)
		(width 0.508)
		(layer "F.Cu")
		(net "P12V")
	)
	(segment
		(start 143.880078 -48.739806)
		(end 144.960086 -48.739806)
		(width 0.508)
		(layer "F.Cu")
		(net "P12V")
	)
	(segment
		(start 147.500086 -43.659806)
		(end 148.580094 -43.659806)
		(width 0.508)
		(layer "F.Cu")
		(net "P12V")
	)
	(segment
		(start 147.500086 -46.199806)
		(end 148.580094 -46.199806)
		(width 0.508)
		(layer "F.Cu")
		(net "P12V")
	)
	(segment
		(start 152.580086 -48.739806)
		(end 153.660094 -48.739806)
		(width 0.508)
		(layer "F.Cu")
		(net "P12V")
	)
	(segment
		(start 150.040086 -47.659798)
		(end 150.040086 -48.739806)
		(width 0.508)
		(layer "F.Cu")
		(net "P12V")
	)
	(segment
		(start 152.580086 -46.199806)
		(end 153.660094 -46.199806)
		(width 0.508)
		(layer "F.Cu")
		(net "P12V")
	)
	(segment
		(start 150.040086 -46.199806)
		(end 150.040086 -47.279814)
		(width 0.508)
		(layer "F.Cu")
		(net "P12V")
	)
	(segment
		(start 147.500086 -46.199806)
		(end 147.500086 -47.279814)
		(width 0.508)
		(layer "F.Cu")
		(net "P12V")
	)
	(segment
		(start 147.500086 -41.119806)
		(end 147.500086 -42.199814)
		(width 0.508)
		(layer "F.Cu")
		(net "P12V")
	)
	(segment
		(start 144.960086 -43.659806)
		(end 144.960086 -44.739814)
		(width 0.508)
		(layer "F.Cu")
		(net "P12V")
	)
	(segment
		(start 150.040086 -45.119798)
		(end 150.040086 -46.199806)
		(width 0.508)
		(layer "F.Cu")
		(net "P12V")
	)
	(segment
		(start 150.040086 -43.659806)
		(end 150.040086 -44.739814)
		(width 0.508)
		(layer "F.Cu")
		(net "P12V")
	)
	(segment
		(start 152.580086 -43.659806)
		(end 152.580086 -44.739814)
		(width 0.508)
		(layer "F.Cu")
		(net "P12V")
	)
	(segment
		(start 144.960086 -41.119806)
		(end 144.960086 -42.199814)
		(width 0.508)
		(layer "F.Cu")
		(net "P12V")
	)
	(segment
		(start 148.960078 -41.119806)
		(end 150.040086 -41.119806)
		(width 0.508)
		(layer "F.Cu")
		(net "P12V")
	)
	(segment
		(start 143.880078 -43.659806)
		(end 144.960086 -43.659806)
		(width 0.508)
		(layer "F.Cu")
		(net "P12V")
	)
	(segment
		(start 150.040086 -46.199806)
		(end 151.120094 -46.199806)
		(width 0.508)
		(layer "F.Cu")
		(net "P12V")
	)
	(segment
		(start 144.960086 -40.039798)
		(end 144.960086 -41.119806)
		(width 0.508)
		(layer "F.Cu")
		(net "P12V")
	)
	(segment
		(start 144.960086 -48.739806)
		(end 144.960086 -49.819814)
		(width 0.508)
		(layer "F.Cu")
		(net "P12V")
	)
	(segment
		(start 151.500078 -43.659806)
		(end 152.580086 -43.659806)
		(width 0.508)
		(layer "F.Cu")
		(net "P12V")
	)
	(segment
		(start 144.960086 -41.119806)
		(end 146.040094 -41.119806)
		(width 0.508)
		(layer "F.Cu")
		(net "P12V")
	)
	(segment
		(start 146.420078 -41.119806)
		(end 147.500086 -41.119806)
		(width 0.508)
		(layer "F.Cu")
		(net "P12V")
	)
	(segment
		(start 148.960078 -43.659806)
		(end 150.040086 -43.659806)
		(width 0.508)
		(layer "F.Cu")
		(net "P12V")
	)
	(via
		(at 14.330426 -37.206428)
		(size 0.7112)
		(drill 0.4064)
		(layers "F.Cu" "B.Cu")
		(net "P12V")
	)
	(via
		(at 6.710426 -42.286428)
		(size 0.7112)
		(drill 0.4064)
		(layers "F.Cu" "B.Cu")
		(net "P12V")
	)
	(via
		(at 76.2 -27.051)
		(size 0.7112)
		(drill 0.4064)
		(layers "F.Cu" "B.Cu")
		(net "P12V")
	)
	(via
		(at 29.570426 -37.206428)
		(size 0.7112)
		(drill 0.4064)
		(layers "F.Cu" "B.Cu")
		(net "P12V")
	)
	(via
		(at 131.170426 -16.886428)
		(size 0.7112)
		(drill 0.4064)
		(layers "F.Cu" "B.Cu")
		(net "P12V")
	)
	(via
		(at 90.530426 -16.886428)
		(size 0.7112)
		(drill 0.4064)
		(layers "F.Cu" "B.Cu")
		(net "P12V")
	)
	(via
		(at 129.748534 -41.938448)
		(size 0.7112)
		(drill 0.4064)
		(layers "F.Cu" "B.Cu")
		(net "P12V")
	)
	(via
		(at 95.610426 -37.206428)
		(size 0.7112)
		(drill 0.4064)
		(layers "F.Cu" "B.Cu")
		(net "P12V")
	)
	(via
		(at 54.970426 -37.206428)
		(size 0.7112)
		(drill 0.4064)
		(layers "F.Cu" "B.Cu")
		(net "P12V")
	)
	(via
		(at 131.170426 -21.966428)
		(size 0.7112)
		(drill 0.4064)
		(layers "F.Cu" "B.Cu")
		(net "P12V")
	)
	(via
		(at 69.723 -27.051)
		(size 0.7112)
		(drill 0.4064)
		(layers "F.Cu" "B.Cu")
		(net "P12V")
	)
	(via
		(at 34.650426 -27.046428)
		(size 0.7112)
		(drill 0.4064)
		(layers "F.Cu" "B.Cu")
		(net "P12V")
	)
	(via
		(at 54.970426 -32.126428)
		(size 0.7112)
		(drill 0.4064)
		(layers "F.Cu" "B.Cu")
		(net "P12V")
	)
	(via
		(at 115.930426 -21.966428)
		(size 0.7112)
		(drill 0.4064)
		(layers "F.Cu" "B.Cu")
		(net "P12V")
	)
	(via
		(at 76.454 -21.971)
		(size 0.7112)
		(drill 0.4064)
		(layers "F.Cu" "B.Cu")
		(net "P12V")
	)
	(via
		(at 70.210426 -42.286428)
		(size 0.7112)
		(drill 0.4064)
		(layers "F.Cu" "B.Cu")
		(net "P12V")
	)
	(via
		(at 65.130426 -21.966428)
		(size 0.7112)
		(drill 0.4064)
		(layers "F.Cu" "B.Cu")
		(net "P12V")
	)
	(via
		(at 114.935 -44.323)
		(size 0.7112)
		(drill 0.4064)
		(layers "F.Cu" "B.Cu")
		(net "P12V")
	)
	(via
		(at 121.010426 -37.206428)
		(size 0.7112)
		(drill 0.4064)
		(layers "F.Cu" "B.Cu")
		(net "P12V")
	)
	(via
		(at 90.530426 -32.126428)
		(size 0.7112)
		(drill 0.4064)
		(layers "F.Cu" "B.Cu")
		(net "P12V")
	)
	(via
		(at 128.681734 -40.871648)
		(size 0.7112)
		(drill 0.4064)
		(layers "F.Cu" "B.Cu")
		(net "P12V")
	)
	(via
		(at 9.250426 -32.126428)
		(size 0.7112)
		(drill 0.4064)
		(layers "F.Cu" "B.Cu")
		(net "P12V")
	)
	(via
		(at 140.442696 -44.481496)
		(size 0.7112)
		(drill 0.4064)
		(layers "F.Cu" "B.Cu")
		(net "P12V")
	)
	(via
		(at 132.971794 -43.427396)
		(size 0.7112)
		(drill 0.4064)
		(layers "F.Cu" "B.Cu")
		(net "P12V")
	)
	(via
		(at 115.930426 -37.206428)
		(size 0.7112)
		(drill 0.4064)
		(layers "F.Cu" "B.Cu")
		(net "P12V")
	)
	(via
		(at 60.050426 -21.966428)
		(size 0.7112)
		(drill 0.4064)
		(layers "F.Cu" "B.Cu")
		(net "P12V")
	)
	(via
		(at 9.250426 -21.966428)
		(size 0.7112)
		(drill 0.4064)
		(layers "F.Cu" "B.Cu")
		(net "P12V")
	)
	(via
		(at 131.170426 -27.046428)
		(size 0.7112)
		(drill 0.4064)
		(layers "F.Cu" "B.Cu")
		(net "P12V")
	)
	(via
		(at 127.65913 -44.36999)
		(size 0.7112)
		(drill 0.4064)
		(layers "F.Cu" "B.Cu")
		(net "P12V")
	)
	(via
		(at 49.890426 -42.286428)
		(size 0.7112)
		(drill 0.4064)
		(layers "F.Cu" "B.Cu")
		(net "P12V")
	)
	(via
		(at 1.630426 -44.826428)
		(size 0.7112)
		(drill 0.4064)
		(layers "F.Cu" "B.Cu")
		(net "P12V")
	)
	(via
		(at 14.330426 -47.366428)
		(size 0.7112)
		(drill 0.4064)
		(layers "F.Cu" "B.Cu")
		(net "P12V")
	)
	(via
		(at 95.610426 -16.886428)
		(size 0.7112)
		(drill 0.4064)
		(layers "F.Cu" "B.Cu")
		(net "P12V")
	)
	(via
		(at 29.570426 -27.046428)
		(size 0.7112)
		(drill 0.4064)
		(layers "F.Cu" "B.Cu")
		(net "P12V")
	)
	(via
		(at 24.490426 -42.286428)
		(size 0.7112)
		(drill 0.4064)
		(layers "F.Cu" "B.Cu")
		(net "P12V")
	)
	(via
		(at 95.610426 -47.366428)
		(size 0.7112)
		(drill 0.4064)
		(layers "F.Cu" "B.Cu")
		(net "P12V")
	)
	(via
		(at 122.235722 -41.87698)
		(size 0.7112)
		(drill 0.4064)
		(layers "F.Cu" "B.Cu")
		(net "P12V")
	)
	(via
		(at 34.650426 -21.966428)
		(size 0.7112)
		(drill 0.4064)
		(layers "F.Cu" "B.Cu")
		(net "P12V")
	)
	(via
		(at 85.450426 -16.886428)
		(size 0.7112)
		(drill 0.4064)
		(layers "F.Cu" "B.Cu")
		(net "P12V")
	)
	(via
		(at 100.690426 -42.286428)
		(size 0.7112)
		(drill 0.4064)
		(layers "F.Cu" "B.Cu")
		(net "P12V")
	)
	(via
		(at 85.450426 -37.206428)
		(size 0.7112)
		(drill 0.4064)
		(layers "F.Cu" "B.Cu")
		(net "P12V")
	)
	(via
		(at 11.912092 -38.845744)
		(size 0.7112)
		(drill 0.3556)
		(layers "F.Cu" "B.Cu")
		(net "P12V")
	)
	(via
		(at 112.8014 -44.323)
		(size 0.7112)
		(drill 0.4064)
		(layers "F.Cu" "B.Cu")
		(net "P12V")
	)
	(via
		(at 131.170426 -32.126428)
		(size 0.7112)
		(drill 0.4064)
		(layers "F.Cu" "B.Cu")
		(net "P12V")
	)
	(via
		(at 49.890426 -16.886428)
		(size 0.7112)
		(drill 0.4064)
		(layers "F.Cu" "B.Cu")
		(net "P12V")
	)
	(via
		(at 116.1034 -44.45)
		(size 0.7112)
		(drill 0.4064)
		(layers "F.Cu" "B.Cu")
		(net "P12V")
	)
	(via
		(at 54.970426 -27.046428)
		(size 0.7112)
		(drill 0.4064)
		(layers "F.Cu" "B.Cu")
		(net "P12V")
	)
	(via
		(at 4.170426 -47.366428)
		(size 0.7112)
		(drill 0.4064)
		(layers "F.Cu" "B.Cu")
		(net "P12V")
	)
	(via
		(at 126.59233 -43.30319)
		(size 0.7112)
		(drill 0.4064)
		(layers "F.Cu" "B.Cu")
		(net "P12V")
	)
	(via
		(at 34.650426 -16.886428)
		(size 0.7112)
		(drill 0.4064)
		(layers "F.Cu" "B.Cu")
		(net "P12V")
	)
	(via
		(at 24.490426 -16.886428)
		(size 0.7112)
		(drill 0.4064)
		(layers "F.Cu" "B.Cu")
		(net "P12V")
	)
	(via
		(at 24.490426 -21.966428)
		(size 0.7112)
		(drill 0.4064)
		(layers "F.Cu" "B.Cu")
		(net "P12V")
	)
	(via
		(at 126.090426 -32.126428)
		(size 0.7112)
		(drill 0.4064)
		(layers "F.Cu" "B.Cu")
		(net "P12V")
	)
	(via
		(at 131.882134 -41.938448)
		(size 0.7112)
		(drill 0.4064)
		(layers "F.Cu" "B.Cu")
		(net "P12V")
	)
	(via
		(at 110.850426 -27.046428)
		(size 0.7112)
		(drill 0.4064)
		(layers "F.Cu" "B.Cu")
		(net "P12V")
	)
	(via
		(at 100.690426 -37.206428)
		(size 0.7112)
		(drill 0.4064)
		(layers "F.Cu" "B.Cu")
		(net "P12V")
	)
	(via
		(at -0.909574 -39.746428)
		(size 0.7112)
		(drill 0.4064)
		(layers "F.Cu" "B.Cu")
		(net "P12V")
	)
	(via
		(at 4.170426 -44.826428)
		(size 0.7112)
		(drill 0.4064)
		(layers "F.Cu" "B.Cu")
		(net "P12V")
	)
	(via
		(at 44.810426 -27.046428)
		(size 0.7112)
		(drill 0.4064)
		(layers "F.Cu" "B.Cu")
		(net "P12V")
	)
	(via
		(at 105.770426 -37.206428)
		(size 0.7112)
		(drill 0.4064)
		(layers "F.Cu" "B.Cu")
		(net "P12V")
	)
	(via
		(at 105.770426 -16.886428)
		(size 0.7112)
		(drill 0.4064)
		(layers "F.Cu" "B.Cu")
		(net "P12V")
	)
	(via
		(at 107.116626 -43.251628)
		(size 0.7112)
		(drill 0.4064)
		(layers "F.Cu" "B.Cu")
		(net "P12V")
	)
	(via
		(at 121.010426 -27.046428)
		(size 0.7112)
		(drill 0.4064)
		(layers "F.Cu" "B.Cu")
		(net "P12V")
	)
	(via
		(at 95.610426 -21.966428)
		(size 0.7112)
		(drill 0.4064)
		(layers "F.Cu" "B.Cu")
		(net "P12V")
	)
	(via
		(at 24.490426 -37.206428)
		(size 0.7112)
		(drill 0.4064)
		(layers "F.Cu" "B.Cu")
		(net "P12V")
	)
	(via
		(at 136.250426 -21.966428)
		(size 0.7112)
		(drill 0.4064)
		(layers "F.Cu" "B.Cu")
		(net "P12V")
	)
	(via
		(at 29.570426 -21.966428)
		(size 0.7112)
		(drill 0.4064)
		(layers "F.Cu" "B.Cu")
		(net "P12V")
	)
	(via
		(at 65.130426 -37.206428)
		(size 0.7112)
		(drill 0.4064)
		(layers "F.Cu" "B.Cu")
		(net "P12V")
	)
	(via
		(at 24.490426 -27.046428)
		(size 0.7112)
		(drill 0.4064)
		(layers "F.Cu" "B.Cu")
		(net "P12V")
	)
	(via
		(at 134.038594 -43.427396)
		(size 0.7112)
		(drill 0.4064)
		(layers "F.Cu" "B.Cu")
		(net "P12V")
	)
	(via
		(at 1.630426 -42.286428)
		(size 0.7112)
		(drill 0.4064)
		(layers "F.Cu" "B.Cu")
		(net "P12V")
	)
	(via
		(at 69.723 -21.971)
		(size 0.7112)
		(drill 0.4064)
		(layers "F.Cu" "B.Cu")
		(net "P12V")
	)
	(via
		(at 4.170426 -42.286428)
		(size 0.7112)
		(drill 0.4064)
		(layers "F.Cu" "B.Cu")
		(net "P12V")
	)
	(via
		(at 123.302522 -41.87698)
		(size 0.7112)
		(drill 0.4064)
		(layers "F.Cu" "B.Cu")
		(net "P12V")
	)
	(via
		(at 140.442696 -43.414696)
		(size 0.7112)
		(drill 0.4064)
		(layers "F.Cu" "B.Cu")
		(net "P12V")
	)
	(via
		(at 115.930426 -32.126428)
		(size 0.7112)
		(drill 0.4064)
		(layers "F.Cu" "B.Cu")
		(net "P12V")
	)
	(via
		(at 19.410426 -42.286428)
		(size 0.7112)
		(drill 0.4064)
		(layers "F.Cu" "B.Cu")
		(net "P12V")
	)
	(via
		(at 80.370426 -27.046428)
		(size 0.7112)
		(drill 0.4064)
		(layers "F.Cu" "B.Cu")
		(net "P12V")
	)
	(via
		(at -0.909574 -42.286428)
		(size 0.7112)
		(drill 0.4064)
		(layers "F.Cu" "B.Cu")
		(net "P12V")
	)
	(via
		(at 29.570426 -47.366428)
		(size 0.7112)
		(drill 0.4064)
		(layers "F.Cu" "B.Cu")
		(net "P12V")
	)
	(via
		(at 90.805 -47.371)
		(size 0.7112)
		(drill 0.4064)
		(layers "F.Cu" "B.Cu")
		(net "P12V")
	)
	(via
		(at 6.710426 -39.746428)
		(size 0.7112)
		(drill 0.4064)
		(layers "F.Cu" "B.Cu")
		(net "P12V")
	)
	(via
		(at 136.163304 -42.042588)
		(size 0.7112)
		(drill 0.4064)
		(layers "F.Cu" "B.Cu")
		(net "P12V")
	)
	(via
		(at 4.170426 -21.966428)
		(size 0.7112)
		(drill 0.4064)
		(layers "F.Cu" "B.Cu")
		(net "P12V")
	)
	(via
		(at 125.436122 -41.87698)
		(size 0.7112)
		(drill 0.4064)
		(layers "F.Cu" "B.Cu")
		(net "P12V")
	)
	(via
		(at 14.330426 -21.966428)
		(size 0.7112)
		(drill 0.4064)
		(layers "F.Cu" "B.Cu")
		(net "P12V")
	)
	(via
		(at 139.375896 -44.481496)
		(size 0.7112)
		(drill 0.4064)
		(layers "F.Cu" "B.Cu")
		(net "P12V")
	)
	(via
		(at 110.5662 -44.323)
		(size 0.7112)
		(drill 0.4064)
		(layers "F.Cu" "B.Cu")
		(net "P12V")
	)
	(via
		(at 100.690426 -27.046428)
		(size 0.7112)
		(drill 0.4064)
		(layers "F.Cu" "B.Cu")
		(net "P12V")
	)
	(via
		(at 39.730426 -47.366428)
		(size 0.7112)
		(drill 0.4064)
		(layers "F.Cu" "B.Cu")
		(net "P12V")
	)
	(via
		(at 60.050426 -27.046428)
		(size 0.7112)
		(drill 0.4064)
		(layers "F.Cu" "B.Cu")
		(net "P12V")
	)
	(via
		(at 11.912092 -46.465744)
		(size 0.7112)
		(drill 0.3556)
		(layers "F.Cu" "B.Cu")
		(net "P12V")
	)
	(via
		(at 88.366092 -29.828744)
		(size 0.7112)
		(drill 0.3556)
		(layers "F.Cu" "B.Cu")
		(net "P12V")
	)
	(via
		(at 105.770426 -21.966428)
		(size 0.7112)
		(drill 0.4064)
		(layers "F.Cu" "B.Cu")
		(net "P12V")
	)
	(via
		(at 75.290426 -47.366428)
		(size 0.7112)
		(drill 0.4064)
		(layers "F.Cu" "B.Cu")
		(net "P12V")
	)
	(via
		(at 127.65913 -43.30319)
		(size 0.7112)
		(drill 0.4064)
		(layers "F.Cu" "B.Cu")
		(net "P12V")
	)
	(via
		(at 133.705092 -29.701744)
		(size 0.7112)
		(drill 0.3556)
		(layers "F.Cu" "B.Cu")
		(net "P12V")
	)
	(via
		(at 121.230136 -43.278044)
		(size 0.7112)
		(drill 0.4064)
		(layers "F.Cu" "B.Cu")
		(net "P12V")
	)
	(via
		(at 116.1034 -43.3832)
		(size 0.7112)
		(drill 0.4064)
		(layers "F.Cu" "B.Cu")
		(net "P12V")
	)
	(via
		(at -0.909574 -37.206428)
		(size 0.7112)
		(drill 0.4064)
		(layers "F.Cu" "B.Cu")
		(net "P12V")
	)
	(via
		(at 135.096504 -42.042588)
		(size 0.7112)
		(drill 0.4064)
		(layers "F.Cu" "B.Cu")
		(net "P12V")
	)
	(via
		(at 34.650426 -32.126428)
		(size 0.7112)
		(drill 0.4064)
		(layers "F.Cu" "B.Cu")
		(net "P12V")
	)
	(via
		(at 146.410426 -32.126428)
		(size 0.7112)
		(drill 0.4064)
		(layers "F.Cu" "B.Cu")
		(net "P12V")
	)
	(via
		(at 110.850426 -21.966428)
		(size 0.7112)
		(drill 0.4064)
		(layers "F.Cu" "B.Cu")
		(net "P12V")
	)
	(via
		(at 108.183426 -43.251628)
		(size 0.7112)
		(drill 0.4064)
		(layers "F.Cu" "B.Cu")
		(net "P12V")
	)
	(via
		(at 90.530426 -27.046428)
		(size 0.7112)
		(drill 0.4064)
		(layers "F.Cu" "B.Cu")
		(net "P12V")
	)
	(via
		(at 111.633 -44.323)
		(size 0.7112)
		(drill 0.4064)
		(layers "F.Cu" "B.Cu")
		(net "P12V")
	)
	(via
		(at 75.290426 -32.126428)
		(size 0.7112)
		(drill 0.4064)
		(layers "F.Cu" "B.Cu")
		(net "P12V")
	)
	(via
		(at 19.410426 -47.366428)
		(size 0.7112)
		(drill 0.4064)
		(layers "F.Cu" "B.Cu")
		(net "P12V")
	)
	(via
		(at 1.630426 -34.666428)
		(size 0.7112)
		(drill 0.4064)
		(layers "F.Cu" "B.Cu")
		(net "P12V")
	)
	(via
		(at 63.881 -42.291)
		(size 0.7112)
		(drill 0.4064)
		(layers "F.Cu" "B.Cu")
		(net "P12V")
	)
	(via
		(at 4.170426 -29.586428)
		(size 0.7112)
		(drill 0.4064)
		(layers "F.Cu" "B.Cu")
		(net "P12V")
	)
	(via
		(at 136.163304 -40.975788)
		(size 0.7112)
		(drill 0.4064)
		(layers "F.Cu" "B.Cu")
		(net "P12V")
	)
	(via
		(at 48.107092 -29.447744)
		(size 0.7112)
		(drill 0.3556)
		(layers "F.Cu" "B.Cu")
		(net "P12V")
	)
	(via
		(at 136.250426 -37.206428)
		(size 0.7112)
		(drill 0.4064)
		(layers "F.Cu" "B.Cu")
		(net "P12V")
	)
	(via
		(at 141.330426 -32.126428)
		(size 0.7112)
		(drill 0.4064)
		(layers "F.Cu" "B.Cu")
		(net "P12V")
	)
	(via
		(at 107.116626 -44.318428)
		(size 0.7112)
		(drill 0.4064)
		(layers "F.Cu" "B.Cu")
		(net "P12V")
	)
	(via
		(at 18.542 -24.003)
		(size 0.7112)
		(drill 0.3556)
		(layers "F.Cu" "B.Cu")
		(net "P12V")
	)
	(via
		(at 6.710426 -34.666428)
		(size 0.7112)
		(drill 0.4064)
		(layers "F.Cu" "B.Cu")
		(net "P12V")
	)
	(via
		(at 95.610426 -32.126428)
		(size 0.7112)
		(drill 0.4064)
		(layers "F.Cu" "B.Cu")
		(net "P12V")
	)
	(via
		(at 6.710426 -29.586428)
		(size 0.7112)
		(drill 0.4064)
		(layers "F.Cu" "B.Cu")
		(net "P12V")
	)
	(via
		(at 135.096504 -40.975788)
		(size 0.7112)
		(drill 0.4064)
		(layers "F.Cu" "B.Cu")
		(net "P12V")
	)
	(via
		(at 60.050426 -32.126428)
		(size 0.7112)
		(drill 0.4064)
		(layers "F.Cu" "B.Cu")
		(net "P12V")
	)
	(via
		(at 106.049826 -43.251628)
		(size 0.7112)
		(drill 0.4064)
		(layers "F.Cu" "B.Cu")
		(net "P12V")
	)
	(via
		(at 105.770426 -32.126428)
		(size 0.7112)
		(drill 0.4064)
		(layers "F.Cu" "B.Cu")
		(net "P12V")
	)
	(via
		(at 121.010426 -21.966428)
		(size 0.7112)
		(drill 0.4064)
		(layers "F.Cu" "B.Cu")
		(net "P12V")
	)
	(via
		(at 118.237 -43.3832)
		(size 0.7112)
		(drill 0.4064)
		(layers "F.Cu" "B.Cu")
		(net "P12V")
	)
	(via
		(at 110.850426 -32.126428)
		(size 0.7112)
		(drill 0.4064)
		(layers "F.Cu" "B.Cu")
		(net "P12V")
	)
	(via
		(at 24.490426 -47.366428)
		(size 0.7112)
		(drill 0.4064)
		(layers "F.Cu" "B.Cu")
		(net "P12V")
	)
	(via
		(at 118.237 -44.45)
		(size 0.7112)
		(drill 0.4064)
		(layers "F.Cu" "B.Cu")
		(net "P12V")
	)
	(via
		(at 124.369322 -41.87698)
		(size 0.7112)
		(drill 0.4064)
		(layers "F.Cu" "B.Cu")
		(net "P12V")
	)
	(via
		(at 24.490426 -32.126428)
		(size 0.7112)
		(drill 0.4064)
		(layers "F.Cu" "B.Cu")
		(net "P12V")
	)
	(via
		(at 109.4994 -44.323)
		(size 0.7112)
		(drill 0.4064)
		(layers "F.Cu" "B.Cu")
		(net "P12V")
	)
	(via
		(at 136.250426 -32.126428)
		(size 0.7112)
		(drill 0.4064)
		(layers "F.Cu" "B.Cu")
		(net "P12V")
	)
	(via
		(at 105.770426 -27.046428)
		(size 0.7112)
		(drill 0.4064)
		(layers "F.Cu" "B.Cu")
		(net "P12V")
	)
	(via
		(at 4.170426 -34.666428)
		(size 0.7112)
		(drill 0.4064)
		(layers "F.Cu" "B.Cu")
		(net "P12V")
	)
	(via
		(at 85.979 -42.164)
		(size 0.7112)
		(drill 0.4064)
		(layers "F.Cu" "B.Cu")
		(net "P12V")
	)
	(via
		(at 14.330426 -32.126428)
		(size 0.7112)
		(drill 0.4064)
		(layers "F.Cu" "B.Cu")
		(net "P12V")
	)
	(via
		(at 80.370426 -16.886428)
		(size 0.7112)
		(drill 0.4064)
		(layers "F.Cu" "B.Cu")
		(net "P12V")
	)
	(via
		(at 19.410426 -21.966428)
		(size 0.7112)
		(drill 0.4064)
		(layers "F.Cu" "B.Cu")
		(net "P12V")
	)
	(via
		(at 106.049826 -44.318428)
		(size 0.7112)
		(drill 0.4064)
		(layers "F.Cu" "B.Cu")
		(net "P12V")
	)
	(via
		(at 124.369322 -40.81018)
		(size 0.7112)
		(drill 0.4064)
		(layers "F.Cu" "B.Cu")
		(net "P12V")
	)
	(via
		(at 29.570426 -42.286428)
		(size 0.7112)
		(drill 0.4064)
		(layers "F.Cu" "B.Cu")
		(net "P12V")
	)
	(via
		(at 85.450426 -21.966428)
		(size 0.7112)
		(drill 0.4064)
		(layers "F.Cu" "B.Cu")
		(net "P12V")
	)
	(via
		(at 95.610426 -27.046428)
		(size 0.7112)
		(drill 0.4064)
		(layers "F.Cu" "B.Cu")
		(net "P12V")
	)
	(via
		(at 80.370426 -37.206428)
		(size 0.7112)
		(drill 0.4064)
		(layers "F.Cu" "B.Cu")
		(net "P12V")
	)
	(via
		(at 100.690426 -16.886428)
		(size 0.7112)
		(drill 0.4064)
		(layers "F.Cu" "B.Cu")
		(net "P12V")
	)
	(via
		(at 105.791 -42.164)
		(size 0.7112)
		(drill 0.4064)
		(layers "F.Cu" "B.Cu")
		(net "P12V")
	)
	(via
		(at 19.410426 -27.046428)
		(size 0.7112)
		(drill 0.4064)
		(layers "F.Cu" "B.Cu")
		(net "P12V")
	)
	(via
		(at 54.970426 -21.966428)
		(size 0.7112)
		(drill 0.4064)
		(layers "F.Cu" "B.Cu")
		(net "P12V")
	)
	(via
		(at 100.690426 -32.126428)
		(size 0.7112)
		(drill 0.4064)
		(layers "F.Cu" "B.Cu")
		(net "P12V")
	)
	(via
		(at 75.290426 -37.206428)
		(size 0.7112)
		(drill 0.4064)
		(layers "F.Cu" "B.Cu")
		(net "P12V")
	)
	(via
		(at 126.090426 -16.886428)
		(size 0.7112)
		(drill 0.4064)
		(layers "F.Cu" "B.Cu")
		(net "P12V")
	)
	(via
		(at 117.1702 -44.45)
		(size 0.7112)
		(drill 0.4064)
		(layers "F.Cu" "B.Cu")
		(net "P12V")
	)
	(via
		(at 100.690426 -47.366428)
		(size 0.7112)
		(drill 0.4064)
		(layers "F.Cu" "B.Cu")
		(net "P12V")
	)
	(via
		(at 109.4994 -43.2562)
		(size 0.7112)
		(drill 0.4064)
		(layers "F.Cu" "B.Cu")
		(net "P12V")
	)
	(via
		(at 65.130426 -16.886428)
		(size 0.7112)
		(drill 0.4064)
		(layers "F.Cu" "B.Cu")
		(net "P12V")
	)
	(via
		(at 70.210426 -37.206428)
		(size 0.7112)
		(drill 0.4064)
		(layers "F.Cu" "B.Cu")
		(net "P12V")
	)
	(via
		(at 34.650426 -47.366428)
		(size 0.7112)
		(drill 0.4064)
		(layers "F.Cu" "B.Cu")
		(net "P12V")
	)
	(via
		(at 138.296904 -42.042588)
		(size 0.7112)
		(drill 0.4064)
		(layers "F.Cu" "B.Cu")
		(net "P12V")
	)
	(via
		(at 85.450426 -47.366428)
		(size 0.7112)
		(drill 0.4064)
		(layers "F.Cu" "B.Cu")
		(net "P12V")
	)
	(via
		(at 54.970426 -42.286428)
		(size 0.7112)
		(drill 0.4064)
		(layers "F.Cu" "B.Cu")
		(net "P12V")
	)
	(via
		(at 137.230104 -40.975788)
		(size 0.7112)
		(drill 0.4064)
		(layers "F.Cu" "B.Cu")
		(net "P12V")
	)
	(via
		(at 80.370426 -21.966428)
		(size 0.7112)
		(drill 0.4064)
		(layers "F.Cu" "B.Cu")
		(net "P12V")
	)
	(via
		(at 90.530426 -21.966428)
		(size 0.7112)
		(drill 0.4064)
		(layers "F.Cu" "B.Cu")
		(net "P12V")
	)
	(via
		(at 76.708 -17.018)
		(size 0.7112)
		(drill 0.4064)
		(layers "F.Cu" "B.Cu")
		(net "P12V")
	)
	(via
		(at 1.630426 -39.746428)
		(size 0.7112)
		(drill 0.4064)
		(layers "F.Cu" "B.Cu")
		(net "P12V")
	)
	(via
		(at 122.235722 -40.81018)
		(size 0.7112)
		(drill 0.4064)
		(layers "F.Cu" "B.Cu")
		(net "P12V")
	)
	(via
		(at 123.302522 -40.81018)
		(size 0.7112)
		(drill 0.4064)
		(layers "F.Cu" "B.Cu")
		(net "P12V")
	)
	(via
		(at 85.450426 -27.046428)
		(size 0.7112)
		(drill 0.4064)
		(layers "F.Cu" "B.Cu")
		(net "P12V")
	)
	(via
		(at 131.170426 -37.206428)
		(size 0.7112)
		(drill 0.4064)
		(layers "F.Cu" "B.Cu")
		(net "P12V")
	)
	(via
		(at 137.230104 -42.042588)
		(size 0.7112)
		(drill 0.4064)
		(layers "F.Cu" "B.Cu")
		(net "P12V")
	)
	(via
		(at 80.645 -47.371)
		(size 0.7112)
		(drill 0.4064)
		(layers "F.Cu" "B.Cu")
		(net "P12V")
	)
	(via
		(at 4.170426 -27.046428)
		(size 0.7112)
		(drill 0.4064)
		(layers "F.Cu" "B.Cu")
		(net "P12V")
	)
	(via
		(at 29.570426 -16.886428)
		(size 0.7112)
		(drill 0.4064)
		(layers "F.Cu" "B.Cu")
		(net "P12V")
	)
	(via
		(at 108.183426 -44.318428)
		(size 0.7112)
		(drill 0.4064)
		(layers "F.Cu" "B.Cu")
		(net "P12V")
	)
	(via
		(at 136.250426 -27.046428)
		(size 0.7112)
		(drill 0.4064)
		(layers "F.Cu" "B.Cu")
		(net "P12V")
	)
	(via
		(at 69.977 -47.371)
		(size 0.7112)
		(drill 0.4064)
		(layers "F.Cu" "B.Cu")
		(net "P12V")
	)
	(via
		(at 6.710426 -32.126428)
		(size 0.7112)
		(drill 0.4064)
		(layers "F.Cu" "B.Cu")
		(net "P12V")
	)
	(via
		(at 110.871 -42.164)
		(size 0.7112)
		(drill 0.4064)
		(layers "F.Cu" "B.Cu")
		(net "P12V")
	)
	(via
		(at 114.935 -43.2562)
		(size 0.7112)
		(drill 0.4064)
		(layers "F.Cu" "B.Cu")
		(net "P12V")
	)
	(via
		(at 113.8682 -43.2562)
		(size 0.7112)
		(drill 0.4064)
		(layers "F.Cu" "B.Cu")
		(net "P12V")
	)
	(via
		(at 19.410426 -32.126428)
		(size 0.7112)
		(drill 0.4064)
		(layers "F.Cu" "B.Cu")
		(net "P12V")
	)
	(via
		(at 6.710426 -44.826428)
		(size 0.7112)
		(drill 0.4064)
		(layers "F.Cu" "B.Cu")
		(net "P12V")
	)
	(via
		(at 126.090426 -21.966428)
		(size 0.7112)
		(drill 0.4064)
		(layers "F.Cu" "B.Cu")
		(net "P12V")
	)
	(via
		(at 100.690426 -21.966428)
		(size 0.7112)
		(drill 0.4064)
		(layers "F.Cu" "B.Cu")
		(net "P12V")
	)
	(via
		(at 112.8014 -43.2562)
		(size 0.7112)
		(drill 0.4064)
		(layers "F.Cu" "B.Cu")
		(net "P12V")
	)
	(via
		(at 9.250426 -37.206428)
		(size 0.7112)
		(drill 0.4064)
		(layers "F.Cu" "B.Cu")
		(net "P12V")
	)
	(via
		(at 60.050426 -16.886428)
		(size 0.7112)
		(drill 0.4064)
		(layers "F.Cu" "B.Cu")
		(net "P12V")
	)
	(via
		(at 60.050426 -47.366428)
		(size 0.7112)
		(drill 0.4064)
		(layers "F.Cu" "B.Cu")
		(net "P12V")
	)
	(via
		(at 39.730426 -32.126428)
		(size 0.7112)
		(drill 0.4064)
		(layers "F.Cu" "B.Cu")
		(net "P12V")
	)
	(via
		(at 131.882134 -40.871648)
		(size 0.7112)
		(drill 0.4064)
		(layers "F.Cu" "B.Cu")
		(net "P12V")
	)
	(via
		(at 141.330426 -27.046428)
		(size 0.7112)
		(drill 0.4064)
		(layers "F.Cu" "B.Cu")
		(net "P12V")
	)
	(via
		(at 138.296904 -40.975788)
		(size 0.7112)
		(drill 0.4064)
		(layers "F.Cu" "B.Cu")
		(net "P12V")
	)
	(via
		(at 14.330426 -16.886428)
		(size 0.7112)
		(drill 0.4064)
		(layers "F.Cu" "B.Cu")
		(net "P12V")
	)
	(via
		(at 117.1702 -43.3832)
		(size 0.7112)
		(drill 0.4064)
		(layers "F.Cu" "B.Cu")
		(net "P12V")
	)
	(via
		(at 4.170426 -37.206428)
		(size 0.7112)
		(drill 0.4064)
		(layers "F.Cu" "B.Cu")
		(net "P12V")
	)
	(via
		(at 44.810426 -42.286428)
		(size 0.7112)
		(drill 0.4064)
		(layers "F.Cu" "B.Cu")
		(net "P12V")
	)
	(via
		(at 19.410426 -16.886428)
		(size 0.7112)
		(drill 0.4064)
		(layers "F.Cu" "B.Cu")
		(net "P12V")
	)
	(via
		(at 65.130426 -47.366428)
		(size 0.7112)
		(drill 0.4064)
		(layers "F.Cu" "B.Cu")
		(net "P12V")
	)
	(via
		(at 111.633 -43.2562)
		(size 0.7112)
		(drill 0.4064)
		(layers "F.Cu" "B.Cu")
		(net "P12V")
	)
	(via
		(at 90.530426 -37.206428)
		(size 0.7112)
		(drill 0.4064)
		(layers "F.Cu" "B.Cu")
		(net "P12V")
	)
	(via
		(at 115.930426 -16.886428)
		(size 0.7112)
		(drill 0.4064)
		(layers "F.Cu" "B.Cu")
		(net "P12V")
	)
	(via
		(at 139.375896 -43.414696)
		(size 0.7112)
		(drill 0.4064)
		(layers "F.Cu" "B.Cu")
		(net "P12V")
	)
	(via
		(at 49.890426 -27.046428)
		(size 0.7112)
		(drill 0.4064)
		(layers "F.Cu" "B.Cu")
		(net "P12V")
	)
	(via
		(at 65.130426 -32.126428)
		(size 0.7112)
		(drill 0.4064)
		(layers "F.Cu" "B.Cu")
		(net "P12V")
	)
	(via
		(at 54.970426 -16.886428)
		(size 0.7112)
		(drill 0.4064)
		(layers "F.Cu" "B.Cu")
		(net "P12V")
	)
	(via
		(at 39.730426 -37.206428)
		(size 0.7112)
		(drill 0.4064)
		(layers "F.Cu" "B.Cu")
		(net "P12V")
	)
	(via
		(at 129.748534 -40.871648)
		(size 0.7112)
		(drill 0.4064)
		(layers "F.Cu" "B.Cu")
		(net "P12V")
	)
	(via
		(at 121.010426 -16.886428)
		(size 0.7112)
		(drill 0.4064)
		(layers "F.Cu" "B.Cu")
		(net "P12V")
	)
	(via
		(at 44.810426 -16.886428)
		(size 0.7112)
		(drill 0.4064)
		(layers "F.Cu" "B.Cu")
		(net "P12V")
	)
	(via
		(at 134.038594 -44.494196)
		(size 0.7112)
		(drill 0.4064)
		(layers "F.Cu" "B.Cu")
		(net "P12V")
	)
	(via
		(at 126.090426 -37.206428)
		(size 0.7112)
		(drill 0.4064)
		(layers "F.Cu" "B.Cu")
		(net "P12V")
	)
	(via
		(at 121.230136 -44.344844)
		(size 0.7112)
		(drill 0.4064)
		(layers "F.Cu" "B.Cu")
		(net "P12V")
	)
	(via
		(at 14.330426 -42.286428)
		(size 0.7112)
		(drill 0.4064)
		(layers "F.Cu" "B.Cu")
		(net "P12V")
	)
	(via
		(at 54.970426 -47.366428)
		(size 0.7112)
		(drill 0.4064)
		(layers "F.Cu" "B.Cu")
		(net "P12V")
	)
	(via
		(at 6.710426 -47.366428)
		(size 0.7112)
		(drill 0.4064)
		(layers "F.Cu" "B.Cu")
		(net "P12V")
	)
	(via
		(at 39.730426 -16.886428)
		(size 0.7112)
		(drill 0.4064)
		(layers "F.Cu" "B.Cu")
		(net "P12V")
	)
	(via
		(at 39.730426 -21.966428)
		(size 0.7112)
		(drill 0.4064)
		(layers "F.Cu" "B.Cu")
		(net "P12V")
	)
	(via
		(at 4.170426 -39.746428)
		(size 0.7112)
		(drill 0.4064)
		(layers "F.Cu" "B.Cu")
		(net "P12V")
	)
	(via
		(at 80.518 -42.291)
		(size 0.7112)
		(drill 0.4064)
		(layers "F.Cu" "B.Cu")
		(net "P12V")
	)
	(via
		(at 39.730426 -42.286428)
		(size 0.7112)
		(drill 0.4064)
		(layers "F.Cu" "B.Cu")
		(net "P12V")
	)
	(via
		(at 90.043 -42.291)
		(size 0.7112)
		(drill 0.4064)
		(layers "F.Cu" "B.Cu")
		(net "P12V")
	)
	(via
		(at 113.8682 -44.323)
		(size 0.7112)
		(drill 0.4064)
		(layers "F.Cu" "B.Cu")
		(net "P12V")
	)
	(via
		(at 9.250426 -47.366428)
		(size 0.7112)
		(drill 0.4064)
		(layers "F.Cu" "B.Cu")
		(net "P12V")
	)
	(via
		(at 34.650426 -42.286428)
		(size 0.7112)
		(drill 0.4064)
		(layers "F.Cu" "B.Cu")
		(net "P12V")
	)
	(via
		(at 39.730426 -27.046428)
		(size 0.7112)
		(drill 0.4064)
		(layers "F.Cu" "B.Cu")
		(net "P12V")
	)
	(via
		(at 115.951 -42.291)
		(size 0.7112)
		(drill 0.4064)
		(layers "F.Cu" "B.Cu")
		(net "P12V")
	)
	(via
		(at 1.630426 -29.586428)
		(size 0.7112)
		(drill 0.4064)
		(layers "F.Cu" "B.Cu")
		(net "P12V")
	)
	(via
		(at 11.912092 -29.955744)
		(size 0.7112)
		(drill 0.3556)
		(layers "F.Cu" "B.Cu")
		(net "P12V")
	)
	(via
		(at 121.010426 -32.126428)
		(size 0.7112)
		(drill 0.4064)
		(layers "F.Cu" "B.Cu")
		(net "P12V")
	)
	(via
		(at 44.810426 -21.966428)
		(size 0.7112)
		(drill 0.4064)
		(layers "F.Cu" "B.Cu")
		(net "P12V")
	)
	(via
		(at 75.057 -42.926)
		(size 0.7112)
		(drill 0.4064)
		(layers "F.Cu" "B.Cu")
		(net "P12V")
	)
	(via
		(at 9.250426 -27.046428)
		(size 0.7112)
		(drill 0.4064)
		(layers "F.Cu" "B.Cu")
		(net "P12V")
	)
	(via
		(at 120.163336 -43.278044)
		(size 0.7112)
		(drill 0.4064)
		(layers "F.Cu" "B.Cu")
		(net "P12V")
	)
	(via
		(at 80.370426 -32.126428)
		(size 0.7112)
		(drill 0.4064)
		(layers "F.Cu" "B.Cu")
		(net "P12V")
	)
	(via
		(at -0.8509 -29.846016)
		(size 0.7112)
		(drill 0.4064)
		(layers "F.Cu" "B.Cu")
		(net "P12V")
	)
	(via
		(at 69.469 -16.891)
		(size 0.7112)
		(drill 0.4064)
		(layers "F.Cu" "B.Cu")
		(net "P12V")
	)
	(via
		(at 120.163336 -44.344844)
		(size 0.7112)
		(drill 0.4064)
		(layers "F.Cu" "B.Cu")
		(net "P12V")
	)
	(via
		(at 49.890426 -37.206428)
		(size 0.7112)
		(drill 0.4064)
		(layers "F.Cu" "B.Cu")
		(net "P12V")
	)
	(via
		(at 146.410426 -27.046428)
		(size 0.7112)
		(drill 0.4064)
		(layers "F.Cu" "B.Cu")
		(net "P12V")
	)
	(via
		(at -0.909574 -44.826428)
		(size 0.7112)
		(drill 0.4064)
		(layers "F.Cu" "B.Cu")
		(net "P12V")
	)
	(via
		(at 49.890426 -47.366428)
		(size 0.7112)
		(drill 0.4064)
		(layers "F.Cu" "B.Cu")
		(net "P12V")
	)
	(via
		(at 1.630426 -32.126428)
		(size 0.7112)
		(drill 0.4064)
		(layers "F.Cu" "B.Cu")
		(net "P12V")
	)
	(via
		(at 49.890426 -21.966428)
		(size 0.7112)
		(drill 0.4064)
		(layers "F.Cu" "B.Cu")
		(net "P12V")
	)
	(via
		(at 132.971794 -44.494196)
		(size 0.7112)
		(drill 0.4064)
		(layers "F.Cu" "B.Cu")
		(net "P12V")
	)
	(via
		(at 110.850426 -37.206428)
		(size 0.7112)
		(drill 0.4064)
		(layers "F.Cu" "B.Cu")
		(net "P12V")
	)
	(via
		(at -0.909574 -34.666428)
		(size 0.7112)
		(drill 0.4064)
		(layers "F.Cu" "B.Cu")
		(net "P12V")
	)
	(via
		(at 49.890426 -32.126428)
		(size 0.7112)
		(drill 0.4064)
		(layers "F.Cu" "B.Cu")
		(net "P12V")
	)
	(via
		(at 29.570426 -32.126428)
		(size 0.7112)
		(drill 0.4064)
		(layers "F.Cu" "B.Cu")
		(net "P12V")
	)
	(via
		(at 141.330426 -21.966428)
		(size 0.7112)
		(drill 0.4064)
		(layers "F.Cu" "B.Cu")
		(net "P12V")
	)
	(via
		(at 126.59233 -44.36999)
		(size 0.7112)
		(drill 0.4064)
		(layers "F.Cu" "B.Cu")
		(net "P12V")
	)
	(via
		(at 44.810426 -32.126428)
		(size 0.7112)
		(drill 0.4064)
		(layers "F.Cu" "B.Cu")
		(net "P12V")
	)
	(via
		(at 1.630426 -37.206428)
		(size 0.7112)
		(drill 0.4064)
		(layers "F.Cu" "B.Cu")
		(net "P12V")
	)
	(via
		(at -0.909574 -32.126428)
		(size 0.7112)
		(drill 0.4064)
		(layers "F.Cu" "B.Cu")
		(net "P12V")
	)
	(via
		(at 34.650426 -37.206428)
		(size 0.7112)
		(drill 0.4064)
		(layers "F.Cu" "B.Cu")
		(net "P12V")
	)
	(via
		(at 128.681734 -41.938448)
		(size 0.7112)
		(drill 0.4064)
		(layers "F.Cu" "B.Cu")
		(net "P12V")
	)
	(via
		(at 141.330426 -37.206428)
		(size 0.7112)
		(drill 0.4064)
		(layers "F.Cu" "B.Cu")
		(net "P12V")
	)
	(via
		(at 14.330426 -27.046428)
		(size 0.7112)
		(drill 0.4064)
		(layers "F.Cu" "B.Cu")
		(net "P12V")
	)
	(via
		(at 136.250426 -16.886428)
		(size 0.7112)
		(drill 0.4064)
		(layers "F.Cu" "B.Cu")
		(net "P12V")
	)
	(via
		(at 60.050426 -37.206428)
		(size 0.7112)
		(drill 0.4064)
		(layers "F.Cu" "B.Cu")
		(net "P12V")
	)
	(via
		(at 70.210426 -32.126428)
		(size 0.7112)
		(drill 0.4064)
		(layers "F.Cu" "B.Cu")
		(net "P12V")
	)
	(via
		(at 4.170426 -32.126428)
		(size 0.7112)
		(drill 0.4064)
		(layers "F.Cu" "B.Cu")
		(net "P12V")
	)
	(via
		(at 110.850426 -16.886428)
		(size 0.7112)
		(drill 0.4064)
		(layers "F.Cu" "B.Cu")
		(net "P12V")
	)
	(via
		(at 19.410426 -37.206428)
		(size 0.7112)
		(drill 0.4064)
		(layers "F.Cu" "B.Cu")
		(net "P12V")
	)
	(via
		(at 96.52 -42.291)
		(size 0.7112)
		(drill 0.4064)
		(layers "F.Cu" "B.Cu")
		(net "P12V")
	)
	(via
		(at 130.815334 -41.938448)
		(size 0.7112)
		(drill 0.4064)
		(layers "F.Cu" "B.Cu")
		(net "P12V")
	)
	(via
		(at 125.436122 -40.81018)
		(size 0.7112)
		(drill 0.4064)
		(layers "F.Cu" "B.Cu")
		(net "P12V")
	)
	(via
		(at 65.130426 -27.046428)
		(size 0.7112)
		(drill 0.4064)
		(layers "F.Cu" "B.Cu")
		(net "P12V")
	)
	(via
		(at 130.815334 -40.871648)
		(size 0.7112)
		(drill 0.4064)
		(layers "F.Cu" "B.Cu")
		(net "P12V")
	)
	(via
		(at 44.810426 -47.366428)
		(size 0.7112)
		(drill 0.4064)
		(layers "F.Cu" "B.Cu")
		(net "P12V")
	)
	(via
		(at 85.450426 -32.126428)
		(size 0.7112)
		(drill 0.4064)
		(layers "F.Cu" "B.Cu")
		(net "P12V")
	)
	(via
		(at 60.050426 -42.286428)
		(size 0.7112)
		(drill 0.4064)
		(layers "F.Cu" "B.Cu")
		(net "P12V")
	)
	(via
		(at 126.090426 -27.046428)
		(size 0.7112)
		(drill 0.4064)
		(layers "F.Cu" "B.Cu")
		(net "P12V")
	)
	(via
		(at 115.930426 -27.046428)
		(size 0.7112)
		(drill 0.4064)
		(layers "F.Cu" "B.Cu")
		(net "P12V")
	)
	(via
		(at 9.250426 -42.286428)
		(size 0.7112)
		(drill 0.4064)
		(layers "F.Cu" "B.Cu")
		(net "P12V")
	)
	(via
		(at 44.810426 -37.206428)
		(size 0.7112)
		(drill 0.4064)
		(layers "F.Cu" "B.Cu")
		(net "P12V")
	)
	(via
		(at 6.710426 -37.206428)
		(size 0.7112)
		(drill 0.4064)
		(layers "F.Cu" "B.Cu")
		(net "P12V")
	)
	(via
		(at 110.5662 -43.2562)
		(size 0.7112)
		(drill 0.4064)
		(layers "F.Cu" "B.Cu")
		(net "P12V")
	)
	(segment
		(start 152.580086 -46.199806)
		(end 152.580086 -47.279814)
		(width 0.508)
		(layer "B.Cu")
		(net "P12V")
	)
	(segment
		(start 146.420078 -43.659806)
		(end 147.500086 -43.659806)
		(width 0.508)
		(layer "B.Cu")
		(net "P12V")
	)
	(segment
		(start 151.500078 -41.119806)
		(end 152.580086 -41.119806)
		(width 0.508)
		(layer "B.Cu")
		(net "P12V")
	)
	(segment
		(start 147.500086 -46.199806)
		(end 147.500086 -47.279814)
		(width 0.508)
		(layer "B.Cu")
		(net "P12V")
	)
	(segment
		(start 148.960078 -48.739806)
		(end 150.040086 -48.739806)
		(width 0.508)
		(layer "B.Cu")
		(net "P12V")
	)
	(segment
		(start 150.040086 -46.199806)
		(end 150.040086 -47.279814)
		(width 0.508)
		(layer "B.Cu")
		(net "P12V")
	)
	(segment
		(start 148.960078 -46.199806)
		(end 150.040086 -46.199806)
		(width 0.508)
		(layer "B.Cu")
		(net "P12V")
	)
	(segment
		(start 143.880078 -48.739806)
		(end 144.960086 -48.739806)
		(width 0.508)
		(layer "B.Cu")
		(net "P12V")
	)
	(segment
		(start 150.040086 -41.119806)
		(end 150.040086 -42.199814)
		(width 0.508)
		(layer "B.Cu")
		(net "P12V")
	)
	(segment
		(start 144.960086 -40.039798)
		(end 144.960086 -41.119806)
		(width 0.508)
		(layer "B.Cu")
		(net "P12V")
	)
	(segment
		(start 144.960086 -47.659798)
		(end 144.960086 -48.739806)
		(width 0.508)
		(layer "B.Cu")
		(net "P12V")
	)
	(segment
		(start 150.040086 -48.739806)
		(end 150.040086 -49.819814)
		(width 0.508)
		(layer "B.Cu")
		(net "P12V")
	)
	(segment
		(start 152.580086 -46.199806)
		(end 153.660094 -46.199806)
		(width 0.508)
		(layer "B.Cu")
		(net "P12V")
	)
	(segment
		(start 147.500086 -40.039798)
		(end 147.500086 -41.119806)
		(width 0.508)
		(layer "B.Cu")
		(net "P12V")
	)
	(segment
		(start 146.420078 -48.739806)
		(end 147.500086 -48.739806)
		(width 0.508)
		(layer "B.Cu")
		(net "P12V")
	)
	(segment
		(start 144.960086 -42.579798)
		(end 144.960086 -43.659806)
		(width 0.508)
		(layer "B.Cu")
		(net "P12V")
	)
	(segment
		(start 144.960086 -46.199806)
		(end 146.040094 -46.199806)
		(width 0.508)
		(layer "B.Cu")
		(net "P12V")
	)
	(segment
		(start 150.040086 -43.659806)
		(end 150.040086 -44.739814)
		(width 0.508)
		(layer "B.Cu")
		(net "P12V")
	)
	(segment
		(start 152.580086 -43.659806)
		(end 152.580086 -44.739814)
		(width 0.508)
		(layer "B.Cu")
		(net "P12V")
	)
	(segment
		(start 144.960086 -48.739806)
		(end 146.040094 -48.739806)
		(width 0.508)
		(layer "B.Cu")
		(net "P12V")
	)
	(segment
		(start 152.580086 -43.659806)
		(end 153.660094 -43.659806)
		(width 0.508)
		(layer "B.Cu")
		(net "P12V")
	)
	(segment
		(start 146.420078 -41.119806)
		(end 147.500086 -41.119806)
		(width 0.508)
		(layer "B.Cu")
		(net "P12V")
	)
	(segment
		(start 147.500086 -41.119806)
		(end 147.500086 -42.199814)
		(width 0.508)
		(layer "B.Cu")
		(net "P12V")
	)
	(segment
		(start 147.500086 -42.579798)
		(end 147.500086 -43.659806)
		(width 0.508)
		(layer "B.Cu")
		(net "P12V")
	)
	(segment
		(start 150.040086 -47.659798)
		(end 150.040086 -48.739806)
		(width 0.508)
		(layer "B.Cu")
		(net "P12V")
	)
	(segment
		(start 144.960086 -43.659806)
		(end 146.040094 -43.659806)
		(width 0.508)
		(layer "B.Cu")
		(net "P12V")
	)
	(segment
		(start 151.500078 -48.739806)
		(end 152.580086 -48.739806)
		(width 0.508)
		(layer "B.Cu")
		(net "P12V")
	)
	(segment
		(start 147.500086 -43.659806)
		(end 147.500086 -44.739814)
		(width 0.508)
		(layer "B.Cu")
		(net "P12V")
	)
	(segment
		(start 144.960086 -45.119798)
		(end 144.960086 -46.199806)
		(width 0.508)
		(layer "B.Cu")
		(net "P12V")
	)
	(segment
		(start 144.960086 -48.739806)
		(end 144.960086 -49.819814)
		(width 0.508)
		(layer "B.Cu")
		(net "P12V")
	)
	(segment
		(start 150.040086 -43.659806)
		(end 151.120094 -43.659806)
		(width 0.508)
		(layer "B.Cu")
		(net "P12V")
	)
	(segment
		(start 144.960086 -46.199806)
		(end 144.960086 -47.279814)
		(width 0.508)
		(layer "B.Cu")
		(net "P12V")
	)
	(segment
		(start 143.880078 -46.199806)
		(end 144.960086 -46.199806)
		(width 0.508)
		(layer "B.Cu")
		(net "P12V")
	)
	(segment
		(start 147.500086 -48.739806)
		(end 147.500086 -49.819814)
		(width 0.508)
		(layer "B.Cu")
		(net "P12V")
	)
	(segment
		(start 147.500086 -43.659806)
		(end 148.580094 -43.659806)
		(width 0.508)
		(layer "B.Cu")
		(net "P12V")
	)
	(segment
		(start 152.580086 -40.039798)
		(end 152.580086 -41.119806)
		(width 0.508)
		(layer "B.Cu")
		(net "P12V")
	)
	(segment
		(start 150.040086 -42.579798)
		(end 150.040086 -43.659806)
		(width 0.508)
		(layer "B.Cu")
		(net "P12V")
	)
	(segment
		(start 148.960078 -43.659806)
		(end 150.040086 -43.659806)
		(width 0.508)
		(layer "B.Cu")
		(net "P12V")
	)
	(segment
		(start 150.040086 -48.739806)
		(end 151.120094 -48.739806)
		(width 0.508)
		(layer "B.Cu")
		(net "P12V")
	)
	(segment
		(start 152.580086 -48.739806)
		(end 153.660094 -48.739806)
		(width 0.508)
		(layer "B.Cu")
		(net "P12V")
	)
	(segment
		(start 148.960078 -41.119806)
		(end 150.040086 -41.119806)
		(width 0.508)
		(layer "B.Cu")
		(net "P12V")
	)
	(segment
		(start 147.500086 -46.199806)
		(end 148.580094 -46.199806)
		(width 0.508)
		(layer "B.Cu")
		(net "P12V")
	)
	(segment
		(start 152.580086 -47.659798)
		(end 152.580086 -48.739806)
		(width 0.508)
		(layer "B.Cu")
		(net "P12V")
	)
	(segment
		(start 143.880078 -41.119806)
		(end 144.960086 -41.119806)
		(width 0.508)
		(layer "B.Cu")
		(net "P12V")
	)
	(segment
		(start 152.580086 -45.119798)
		(end 152.580086 -46.199806)
		(width 0.508)
		(layer "B.Cu")
		(net "P12V")
	)
	(segment
		(start 150.040086 -45.119798)
		(end 150.040086 -46.199806)
		(width 0.508)
		(layer "B.Cu")
		(net "P12V")
	)
	(segment
		(start 144.960086 -41.119806)
		(end 146.040094 -41.119806)
		(width 0.508)
		(layer "B.Cu")
		(net "P12V")
	)
	(segment
		(start 147.500086 -41.119806)
		(end 148.580094 -41.119806)
		(width 0.508)
		(layer "B.Cu")
		(net "P12V")
	)
	(segment
		(start 143.880078 -43.659806)
		(end 144.960086 -43.659806)
		(width 0.508)
		(layer "B.Cu")
		(net "P12V")
	)
	(segment
		(start 150.040086 -40.039798)
		(end 150.040086 -41.119806)
		(width 0.508)
		(layer "B.Cu")
		(net "P12V")
	)
	(segment
		(start 150.040086 -41.119806)
		(end 151.120094 -41.119806)
		(width 0.508)
		(layer "B.Cu")
		(net "P12V")
	)
	(segment
		(start 144.960086 -43.659806)
		(end 144.960086 -44.739814)
		(width 0.508)
		(layer "B.Cu")
		(net "P12V")
	)
	(segment
		(start 152.580086 -42.579798)
		(end 152.580086 -43.659806)
		(width 0.508)
		(layer "B.Cu")
		(net "P12V")
	)
	(segment
		(start 152.580086 -41.119806)
		(end 153.660094 -41.119806)
		(width 0.508)
		(layer "B.Cu")
		(net "P12V")
	)
	(segment
		(start 147.500086 -47.659798)
		(end 147.500086 -48.739806)
		(width 0.508)
		(layer "B.Cu")
		(net "P12V")
	)
	(segment
		(start 150.040086 -46.199806)
		(end 151.120094 -46.199806)
		(width 0.508)
		(layer "B.Cu")
		(net "P12V")
	)
	(segment
		(start 152.580086 -48.739806)
		(end 152.580086 -49.819814)
		(width 0.508)
		(layer "B.Cu")
		(net "P12V")
	)
	(segment
		(start 152.580086 -41.119806)
		(end 152.580086 -42.199814)
		(width 0.508)
		(layer "B.Cu")
		(net "P12V")
	)
	(segment
		(start 147.500086 -48.739806)
		(end 148.580094 -48.739806)
		(width 0.508)
		(layer "B.Cu")
		(net "P12V")
	)
	(segment
		(start 144.960086 -41.119806)
		(end 144.960086 -42.199814)
		(width 0.508)
		(layer "B.Cu")
		(net "P12V")
	)
	(segment
		(start 146.420078 -46.199806)
		(end 147.500086 -46.199806)
		(width 0.508)
		(layer "B.Cu")
		(net "P12V")
	)
	(segment
		(start 151.500078 -46.199806)
		(end 152.580086 -46.199806)
		(width 0.508)
		(layer "B.Cu")
		(net "P12V")
	)
	(segment
		(start 147.500086 -45.119798)
		(end 147.500086 -46.199806)
		(width 0.508)
		(layer "B.Cu")
		(net "P12V")
	)
	(segment
		(start 151.500078 -43.659806)
		(end 152.580086 -43.659806)
		(width 0.508)
		(layer "B.Cu")
		(net "P12V")
	)
	(segment
		(start 133.6675 -82.804)
		(end 133.6675 -83.531964)
		(width 0.1397)
		(layer "F.Cu")
		(net "TRAY PRESENT_OUT#_C")
	)
	(segment
		(start 134.375144 -81.080356)
		(end 134.375144 -78.321408)
		(width 0.1397)
		(layer "F.Cu")
		(net "TRAY PRESENT_OUT#_C")
	)
	(segment
		(start 133.6675 -82.804)
		(end 133.6675 -81.788)
		(width 0.1397)
		(layer "F.Cu")
		(net "TRAY PRESENT_OUT#_C")
	)
	(segment
		(start 133.6675 -81.788)
		(end 134.375144 -81.080356)
		(width 0.1397)
		(layer "F.Cu")
		(net "TRAY PRESENT_OUT#_C")
	)
	(segment
		(start 133.6675 -83.531964)
		(end 133.321552 -83.877912)
		(width 0.1397)
		(layer "F.Cu")
		(net "TRAY PRESENT_OUT#_C")
	)
	(via
		(at 133.321552 -83.877912)
		(size 0.7112)
		(drill 0.3556)
		(layers "F.Cu" "B.Cu")
		(net "TRAY PRESENT_OUT#_C")
	)
	(segment
		(start -1.676908 -90.729308)
		(end -6.99897 -90.729308)
		(width 0.762)
		(layer "F.Cu")
		(net "GND")
	)
	(segment
		(start 133.390894 -80.226408)
		(end 133.390894 -78.994)
		(width 0.762)
		(layer "F.Cu")
		(net "GND")
	)
	(segment
		(start 135.556244 -82.906108)
		(end 136.432544 -82.906108)
		(width 0.508)
		(layer "F.Cu")
		(net "GND")
	)
	(segment
		(start 14.625828 -91.481402)
		(end 14.937486 -91.169744)
		(width 0.381)
		(layer "F.Cu")
		(net "GND")
	)
	(segment
		(start 137.795 -65.524634)
		(end 138.8364 -65.524634)
		(width 0.508)
		(layer "F.Cu")
		(net "GND")
	)
	(segment
		(start 14.625828 -92.291408)
		(end 14.625828 -91.481402)
		(width 0.381)
		(layer "F.Cu")
		(net "GND")
	)
	(segment
		(start 14.937486 -91.169744)
		(end 15.722092 -91.169744)
		(width 0.381)
		(layer "F.Cu")
		(net "GND")
	)
	(segment
		(start -6.99897 -83.109308)
		(end -1.803908 -83.109308)
		(width 0.762)
		(layer "F.Cu")
		(net "GND")
	)
	(via
		(at 54.82082 -112.385856)
		(size 0.7112)
		(drill 0.4064)
		(layers "F.Cu" "B.Cu")
		(net "GND")
	)
	(via
		(at 153.014426 -6.726428)
		(size 0.7112)
		(drill 0.4064)
		(layers "F.Cu" "B.Cu")
		(net "GND")
	)
	(via
		(at 85.699092 -72.881744)
		(size 0.7112)
		(drill 0.4064)
		(layers "F.Cu" "B.Cu")
		(net "GND")
	)
	(via
		(at 65.379092 -57.641744)
		(size 0.7112)
		(drill 0.4064)
		(layers "F.Cu" "B.Cu")
		(net "GND")
	)
	(via
		(at 34.899092 -67.801744)
		(size 0.7112)
		(drill 0.4064)
		(layers "F.Cu" "B.Cu")
		(net "GND")
	)
	(via
		(at 131.75869 -53.481478)
		(size 0.7112)
		(drill 0.4064)
		(layers "F.Cu" "B.Cu")
		(net "GND")
	)
	(via
		(at 111.6838 -50.165)
		(size 0.7112)
		(drill 0.4064)
		(layers "F.Cu" "B.Cu")
		(net "GND")
	)
	(via
		(at 85.450426 -11.806428)
		(size 0.7112)
		(drill 0.4064)
		(layers "F.Cu" "B.Cu")
		(net "GND")
	)
	(via
		(at 124.968 -81.534)
		(size 0.7112)
		(drill 0.4064)
		(layers "F.Cu" "B.Cu")
		(net "GND")
	)
	(via
		(at 135.096758 -52.372006)
		(size 0.7112)
		(drill 0.4064)
		(layers "F.Cu" "B.Cu")
		(net "GND")
	)
	(via
		(at 91.414092 -118.220744)
		(size 0.7112)
		(drill 0.4064)
		(layers "F.Cu" "B.Cu")
		(net "GND")
	)
	(via
		(at 75.539092 -67.801744)
		(size 0.7112)
		(drill 0.4064)
		(layers "F.Cu" "B.Cu")
		(net "GND")
	)
	(via
		(at 111.099092 -57.641744)
		(size 0.7112)
		(drill 0.4064)
		(layers "F.Cu" "B.Cu")
		(net "GND")
	)
	(via
		(at 70.210426 -6.726428)
		(size 0.7112)
		(drill 0.4064)
		(layers "F.Cu" "B.Cu")
		(net "GND")
	)
	(via
		(at 100.939092 -62.721744)
		(size 0.7112)
		(drill 0.4064)
		(layers "F.Cu" "B.Cu")
		(net "GND")
	)
	(via
		(at 90.530426 -11.806428)
		(size 0.7112)
		(drill 0.4064)
		(layers "F.Cu" "B.Cu")
		(net "GND")
	)
	(via
		(at 135.636 -71.628)
		(size 0.7112)
		(drill 0.4064)
		(layers "F.Cu" "B.Cu")
		(net "GND")
	)
	(via
		(at -0.660908 -80.374744)
		(size 0.7112)
		(drill 0.4064)
		(layers "F.Cu" "B.Cu")
		(net "GND")
	)
	(via
		(at 80.619092 -62.721744)
		(size 0.7112)
		(drill 0.4064)
		(layers "F.Cu" "B.Cu")
		(net "GND")
	)
	(via
		(at 50.774092 -118.220744)
		(size 0.7112)
		(drill 0.4064)
		(layers "F.Cu" "B.Cu")
		(net "GND")
	)
	(via
		(at 1.752092 -98.408744)
		(size 0.7112)
		(drill 0.4064)
		(layers "F.Cu" "B.Cu")
		(net "GND")
	)
	(via
		(at 4.419092 -70.341744)
		(size 0.7112)
		(drill 0.4064)
		(layers "F.Cu" "B.Cu")
		(net "GND")
	)
	(via
		(at 44.53382 -96.002856)
		(size 0.7112)
		(drill 0.4064)
		(layers "F.Cu" "B.Cu")
		(net "GND")
	)
	(via
		(at 4.419092 -72.881744)
		(size 0.7112)
		(drill 0.4064)
		(layers "F.Cu" "B.Cu")
		(net "GND")
	)
	(via
		(at 96.494092 -118.220744)
		(size 0.7112)
		(drill 0.4064)
		(layers "F.Cu" "B.Cu")
		(net "GND")
	)
	(via
		(at 50.139092 -62.721744)
		(size 0.7112)
		(drill 0.4064)
		(layers "F.Cu" "B.Cu")
		(net "GND")
	)
	(via
		(at 141.330426 -16.886428)
		(size 0.7112)
		(drill 0.4064)
		(layers "F.Cu" "B.Cu")
		(net "GND")
	)
	(via
		(at 12.293092 -69.833744)
		(size 0.7112)
		(drill 0.3556)
		(layers "F.Cu" "B.Cu")
		(net "GND")
	)
	(via
		(at 50.139092 -67.801744)
		(size 0.7112)
		(drill 0.4064)
		(layers "F.Cu" "B.Cu")
		(net "GND")
	)
	(via
		(at 34.899092 -57.641744)
		(size 0.7112)
		(drill 0.4064)
		(layers "F.Cu" "B.Cu")
		(net "GND")
	)
	(via
		(at 125.831092 -96.122744)
		(size 0.7112)
		(drill 0.4064)
		(layers "F.Cu" "B.Cu")
		(net "GND")
	)
	(via
		(at 80.619092 -67.801744)
		(size 0.7112)
		(drill 0.4064)
		(layers "F.Cu" "B.Cu")
		(net "GND")
	)
	(via
		(at 105.49382 -96.002856)
		(size 0.7112)
		(drill 0.4064)
		(layers "F.Cu" "B.Cu")
		(net "GND")
	)
	(via
		(at 161.010092 -22.081744)
		(size 0.7112)
		(drill 0.4064)
		(layers "F.Cu" "B.Cu")
		(net "GND")
	)
	(via
		(at 112.9792 -51.2318)
		(size 0.7112)
		(drill 0.4064)
		(layers "F.Cu" "B.Cu")
		(net "GND")
	)
	(via
		(at 90.530426 -1.646428)
		(size 0.7112)
		(drill 0.4064)
		(layers "F.Cu" "B.Cu")
		(net "GND")
	)
	(via
		(at 157.383226 -11.806428)
		(size 0.7112)
		(drill 0.4064)
		(layers "F.Cu" "B.Cu")
		(net "GND")
	)
	(via
		(at 24.21382 -106.162856)
		(size 0.7112)
		(drill 0.4064)
		(layers "F.Cu" "B.Cu")
		(net "GND")
	)
	(via
		(at 39.730426 -11.806428)
		(size 0.7112)
		(drill 0.4064)
		(layers "F.Cu" "B.Cu")
		(net "GND")
	)
	(via
		(at 52.933092 -110.092744)
		(size 0.7112)
		(drill 0.3556)
		(layers "F.Cu" "B.Cu")
		(net "GND")
	)
	(via
		(at 1.879092 -65.261744)
		(size 0.7112)
		(drill 0.4064)
		(layers "F.Cu" "B.Cu")
		(net "GND")
	)
	(via
		(at 160.02 -98.425)
		(size 0.7112)
		(drill 0.4064)
		(layers "F.Cu" "B.Cu")
		(net "GND")
	)
	(via
		(at 45.059092 -67.801744)
		(size 0.7112)
		(drill 0.4064)
		(layers "F.Cu" "B.Cu")
		(net "GND")
	)
	(via
		(at 1.752092 -113.140744)
		(size 0.7112)
		(drill 0.4064)
		(layers "F.Cu" "B.Cu")
		(net "GND")
	)
	(via
		(at 125.831092 -85.962744)
		(size 0.7112)
		(drill 0.4064)
		(layers "F.Cu" "B.Cu")
		(net "GND")
	)
	(via
		(at 39.979092 -62.721744)
		(size 0.7112)
		(drill 0.4064)
		(layers "F.Cu" "B.Cu")
		(net "GND")
	)
	(via
		(at 34.899092 -72.881744)
		(size 0.7112)
		(drill 0.4064)
		(layers "F.Cu" "B.Cu")
		(net "GND")
	)
	(via
		(at 6.959092 -72.881744)
		(size 0.7112)
		(drill 0.4064)
		(layers "F.Cu" "B.Cu")
		(net "GND")
	)
	(via
		(at 99.883214 -60.956952)
		(size 0.7112)
		(drill 0.3556)
		(layers "F.Cu" "B.Cu")
		(net "GND")
	)
	(via
		(at 90.25382 -90.922856)
		(size 0.7112)
		(drill 0.4064)
		(layers "F.Cu" "B.Cu")
		(net "GND")
	)
	(via
		(at 133.390894 -78.994)
		(size 0.7112)
		(drill 0.4064)
		(layers "F.Cu" "B.Cu")
		(net "GND")
	)
	(via
		(at 130.69189 -53.481478)
		(size 0.7112)
		(drill 0.4064)
		(layers "F.Cu" "B.Cu")
		(net "GND")
	)
	(via
		(at 117.348 -51.2318)
		(size 0.7112)
		(drill 0.4064)
		(layers "F.Cu" "B.Cu")
		(net "GND")
	)
	(via
		(at 121.180098 -51.097688)
		(size 0.7112)
		(drill 0.4064)
		(layers "F.Cu" "B.Cu")
		(net "GND")
	)
	(via
		(at 100.41382 -90.922856)
		(size 0.7112)
		(drill 0.4064)
		(layers "F.Cu" "B.Cu")
		(net "GND")
	)
	(via
		(at 65.379092 -67.801744)
		(size 0.7112)
		(drill 0.4064)
		(layers "F.Cu" "B.Cu")
		(net "GND")
	)
	(via
		(at 54.970426 -11.806428)
		(size 0.7112)
		(drill 0.4064)
		(layers "F.Cu" "B.Cu")
		(net "GND")
	)
	(via
		(at 106.019092 -52.434744)
		(size 0.7112)
		(drill 0.4064)
		(layers "F.Cu" "B.Cu")
		(net "GND")
	)
	(via
		(at 70.210426 -1.646428)
		(size 0.7112)
		(drill 0.4064)
		(layers "F.Cu" "B.Cu")
		(net "GND")
	)
	(via
		(at 24.21382 -96.002856)
		(size 0.7112)
		(drill 0.4064)
		(layers "F.Cu" "B.Cu")
		(net "GND")
	)
	(via
		(at 105.49382 -85.842856)
		(size 0.7112)
		(drill 0.4064)
		(layers "F.Cu" "B.Cu")
		(net "GND")
	)
	(via
		(at 14.330426 -11.806428)
		(size 0.7112)
		(drill 0.4064)
		(layers "F.Cu" "B.Cu")
		(net "GND")
	)
	(via
		(at 21.67382 -112.512856)
		(size 0.7112)
		(drill 0.4064)
		(layers "F.Cu" "B.Cu")
		(net "GND")
	)
	(via
		(at 95.33382 -85.842856)
		(size 0.7112)
		(drill 0.4064)
		(layers "F.Cu" "B.Cu")
		(net "GND")
	)
	(via
		(at 60.299092 -67.801744)
		(size 0.7112)
		(drill 0.4064)
		(layers "F.Cu" "B.Cu")
		(net "GND")
	)
	(via
		(at 135.864092 -66.404744)
		(size 0.7112)
		(drill 0.3556)
		(layers "F.Cu" "B.Cu")
		(net "GND")
	)
	(via
		(at 105.770426 -1.646428)
		(size 0.7112)
		(drill 0.4064)
		(layers "F.Cu" "B.Cu")
		(net "GND")
	)
	(via
		(at 4.419092 -67.801744)
		(size 0.7112)
		(drill 0.4064)
		(layers "F.Cu" "B.Cu")
		(net "GND")
	)
	(via
		(at 109.5502 -51.2318)
		(size 0.7112)
		(drill 0.4064)
		(layers "F.Cu" "B.Cu")
		(net "GND")
	)
	(via
		(at 134.051294 -50.960528)
		(size 0.7112)
		(drill 0.4064)
		(layers "F.Cu" "B.Cu")
		(net "GND")
	)
	(via
		(at 44.810426 -6.726428)
		(size 0.7112)
		(drill 0.4064)
		(layers "F.Cu" "B.Cu")
		(net "GND")
	)
	(via
		(at 75.01382 -90.922856)
		(size 0.7112)
		(drill 0.4064)
		(layers "F.Cu" "B.Cu")
		(net "GND")
	)
	(via
		(at 29.819092 -62.721744)
		(size 0.7112)
		(drill 0.4064)
		(layers "F.Cu" "B.Cu")
		(net "GND")
	)
	(via
		(at 85.699092 -57.641744)
		(size 0.7112)
		(drill 0.4064)
		(layers "F.Cu" "B.Cu")
		(net "GND")
	)
	(via
		(at 85.450426 -6.726428)
		(size 0.7112)
		(drill 0.4064)
		(layers "F.Cu" "B.Cu")
		(net "GND")
	)
	(via
		(at 24.490426 -11.806428)
		(size 0.7112)
		(drill 0.4064)
		(layers "F.Cu" "B.Cu")
		(net "GND")
	)
	(via
		(at 136.163558 -52.372006)
		(size 0.7112)
		(drill 0.4064)
		(layers "F.Cu" "B.Cu")
		(net "GND")
	)
	(via
		(at 6.959092 -67.801744)
		(size 0.7112)
		(drill 0.4064)
		(layers "F.Cu" "B.Cu")
		(net "GND")
	)
	(via
		(at 75.539092 -62.721744)
		(size 0.7112)
		(drill 0.4064)
		(layers "F.Cu" "B.Cu")
		(net "GND")
	)
	(via
		(at 34.37382 -106.162856)
		(size 0.7112)
		(drill 0.4064)
		(layers "F.Cu" "B.Cu")
		(net "GND")
	)
	(via
		(at 54.69382 -96.002856)
		(size 0.7112)
		(drill 0.4064)
		(layers "F.Cu" "B.Cu")
		(net "GND")
	)
	(via
		(at 123.291092 -94.598744)
		(size 0.7112)
		(drill 0.3556)
		(layers "F.Cu" "B.Cu")
		(net "GND")
	)
	(via
		(at 95.610426 -11.806428)
		(size 0.7112)
		(drill 0.4064)
		(layers "F.Cu" "B.Cu")
		(net "GND")
	)
	(via
		(at 76.301092 -72.881744)
		(size 0.7112)
		(drill 0.4064)
		(layers "F.Cu" "B.Cu")
		(net "GND")
	)
	(via
		(at 55.219092 -62.721744)
		(size 0.7112)
		(drill 0.4064)
		(layers "F.Cu" "B.Cu")
		(net "GND")
	)
	(via
		(at 24.739092 -57.641744)
		(size 0.7112)
		(drill 0.4064)
		(layers "F.Cu" "B.Cu")
		(net "GND")
	)
	(via
		(at 59.77382 -96.002856)
		(size 0.7112)
		(drill 0.4064)
		(layers "F.Cu" "B.Cu")
		(net "GND")
	)
	(via
		(at 49.61382 -106.162856)
		(size 0.7112)
		(drill 0.4064)
		(layers "F.Cu" "B.Cu")
		(net "GND")
	)
	(via
		(at 90.25382 -85.842856)
		(size 0.7112)
		(drill 0.4064)
		(layers "F.Cu" "B.Cu")
		(net "GND")
	)
	(via
		(at 135.096758 -53.438806)
		(size 0.7112)
		(drill 0.4064)
		(layers "F.Cu" "B.Cu")
		(net "GND")
	)
	(via
		(at 106.273092 -72.881744)
		(size 0.7112)
		(drill 0.4064)
		(layers "F.Cu" "B.Cu")
		(net "GND")
	)
	(via
		(at 107.315 -51.2318)
		(size 0.7112)
		(drill 0.4064)
		(layers "F.Cu" "B.Cu")
		(net "GND")
	)
	(via
		(at 45.059092 -62.721744)
		(size 0.7112)
		(drill 0.4064)
		(layers "F.Cu" "B.Cu")
		(net "GND")
	)
	(via
		(at 128.39954 -112.42548)
		(size 0.7112)
		(drill 0.4064)
		(layers "F.Cu" "B.Cu")
		(net "GND")
	)
	(via
		(at 70.459092 -67.801744)
		(size 0.7112)
		(drill 0.4064)
		(layers "F.Cu" "B.Cu")
		(net "GND")
	)
	(via
		(at 1.879092 -52.561744)
		(size 0.7112)
		(drill 0.4064)
		(layers "F.Cu" "B.Cu")
		(net "GND")
	)
	(via
		(at 120.113298 -51.097688)
		(size 0.7112)
		(drill 0.4064)
		(layers "F.Cu" "B.Cu")
		(net "GND")
	)
	(via
		(at 90.25382 -96.002856)
		(size 0.7112)
		(drill 0.4064)
		(layers "F.Cu" "B.Cu")
		(net "GND")
	)
	(via
		(at -0.660908 -52.561744)
		(size 0.7112)
		(drill 0.4064)
		(layers "F.Cu" "B.Cu")
		(net "GND")
	)
	(via
		(at 111.099092 -62.721744)
		(size 0.7112)
		(drill 0.4064)
		(layers "F.Cu" "B.Cu")
		(net "GND")
	)
	(via
		(at 80.619092 -52.434744)
		(size 0.7112)
		(drill 0.4064)
		(layers "F.Cu" "B.Cu")
		(net "GND")
	)
	(via
		(at 106.019092 -57.641744)
		(size 0.7112)
		(drill 0.4064)
		(layers "F.Cu" "B.Cu")
		(net "GND")
	)
	(via
		(at 115.671092 -91.042744)
		(size 0.7112)
		(drill 0.4064)
		(layers "F.Cu" "B.Cu")
		(net "GND")
	)
	(via
		(at 100.939092 -57.641744)
		(size 0.7112)
		(drill 0.4064)
		(layers "F.Cu" "B.Cu")
		(net "GND")
	)
	(via
		(at 49.61382 -90.922856)
		(size 0.7112)
		(drill 0.4064)
		(layers "F.Cu" "B.Cu")
		(net "GND")
	)
	(via
		(at 126.339092 -62.721744)
		(size 0.7112)
		(drill 0.4064)
		(layers "F.Cu" "B.Cu")
		(net "GND")
	)
	(via
		(at 126.974092 -118.220744)
		(size 0.7112)
		(drill 0.4064)
		(layers "F.Cu" "B.Cu")
		(net "GND")
	)
	(via
		(at 34.37382 -90.922856)
		(size 0.7112)
		(drill 0.4064)
		(layers "F.Cu" "B.Cu")
		(net "GND")
	)
	(via
		(at 139.438634 -49.955958)
		(size 0.7112)
		(drill 0.4064)
		(layers "F.Cu" "B.Cu")
		(net "GND")
	)
	(via
		(at 8.864092 -87.613744)
		(size 0.7112)
		(drill 0.4064)
		(layers "F.Cu" "B.Cu")
		(net "GND")
	)
	(via
		(at 95.33382 -106.162856)
		(size 0.7112)
		(drill 0.4064)
		(layers "F.Cu" "B.Cu")
		(net "GND")
	)
	(via
		(at 139.908026 -11.806428)
		(size 0.7112)
		(drill 0.4064)
		(layers "F.Cu" "B.Cu")
		(net "GND")
	)
	(via
		(at 155.258262 -16.688054)
		(size 0.7112)
		(drill 0.4064)
		(layers "F.Cu" "B.Cu")
		(net "GND")
	)
	(via
		(at 54.970426 -1.646428)
		(size 0.7112)
		(drill 0.4064)
		(layers "F.Cu" "B.Cu")
		(net "GND")
	)
	(via
		(at 145.700242 -17.009618)
		(size 0.7112)
		(drill 0.4064)
		(layers "F.Cu" "B.Cu")
		(net "GND")
	)
	(via
		(at 55.219092 -72.881744)
		(size 0.7112)
		(drill 0.4064)
		(layers "F.Cu" "B.Cu")
		(net "GND")
	)
	(via
		(at 9.339326 -57.641744)
		(size 0.7112)
		(drill 0.4064)
		(layers "F.Cu" "B.Cu")
		(net "GND")
	)
	(via
		(at 139.438634 -51.022758)
		(size 0.7112)
		(drill 0.4064)
		(layers "F.Cu" "B.Cu")
		(net "GND")
	)
	(via
		(at 116.179092 -52.434744)
		(size 0.7112)
		(drill 0.4064)
		(layers "F.Cu" "B.Cu")
		(net "GND")
	)
	(via
		(at 15.748 -112.395)
		(size 0.7112)
		(drill 0.4064)
		(layers "F.Cu" "B.Cu")
		(net "GND")
	)
	(via
		(at 34.650426 -11.806428)
		(size 0.7112)
		(drill 0.4064)
		(layers "F.Cu" "B.Cu")
		(net "GND")
	)
	(via
		(at 106.019092 -62.721744)
		(size 0.7112)
		(drill 0.4064)
		(layers "F.Cu" "B.Cu")
		(net "GND")
	)
	(via
		(at 59.77382 -106.162856)
		(size 0.7112)
		(drill 0.4064)
		(layers "F.Cu" "B.Cu")
		(net "GND")
	)
	(via
		(at 95.33382 -90.922856)
		(size 0.7112)
		(drill 0.4064)
		(layers "F.Cu" "B.Cu")
		(net "GND")
	)
	(via
		(at 80.09382 -90.922856)
		(size 0.7112)
		(drill 0.4064)
		(layers "F.Cu" "B.Cu")
		(net "GND")
	)
	(via
		(at 124.132594 -52.476908)
		(size 0.7112)
		(drill 0.4064)
		(layers "F.Cu" "B.Cu")
		(net "GND")
	)
	(via
		(at 157.383226 -1.646428)
		(size 0.7112)
		(drill 0.4064)
		(layers "F.Cu" "B.Cu")
		(net "GND")
	)
	(via
		(at 54.69382 -90.922856)
		(size 0.7112)
		(drill 0.4064)
		(layers "F.Cu" "B.Cu")
		(net "GND")
	)
	(via
		(at 1.879092 -60.181744)
		(size 0.7112)
		(drill 0.4064)
		(layers "F.Cu" "B.Cu")
		(net "GND")
	)
	(via
		(at 90.779092 -57.641744)
		(size 0.7112)
		(drill 0.4064)
		(layers "F.Cu" "B.Cu")
		(net "GND")
	)
	(via
		(at 10.134092 -118.220744)
		(size 0.7112)
		(drill 0.4064)
		(layers "F.Cu" "B.Cu")
		(net "GND")
	)
	(via
		(at 71.094092 -118.220744)
		(size 0.7112)
		(drill 0.4064)
		(layers "F.Cu" "B.Cu")
		(net "GND")
	)
	(via
		(at 49.890426 -6.726428)
		(size 0.7112)
		(drill 0.4064)
		(layers "F.Cu" "B.Cu")
		(net "GND")
	)
	(via
		(at 100.54082 -112.385856)
		(size 0.7112)
		(drill 0.4064)
		(layers "F.Cu" "B.Cu")
		(net "GND")
	)
	(via
		(at 144.276826 -6.726428)
		(size 0.7112)
		(drill 0.4064)
		(layers "F.Cu" "B.Cu")
		(net "GND")
	)
	(via
		(at 126.746 -106.299)
		(size 0.7112)
		(drill 0.4064)
		(layers "F.Cu" "B.Cu")
		(net "GND")
	)
	(via
		(at 59.90082 -112.385856)
		(size 0.7112)
		(drill 0.4064)
		(layers "F.Cu" "B.Cu")
		(net "GND")
	)
	(via
		(at 29.565092 -72.881744)
		(size 0.7112)
		(drill 0.4064)
		(layers "F.Cu" "B.Cu")
		(net "GND")
	)
	(via
		(at 105.49382 -90.922856)
		(size 0.7112)
		(drill 0.4064)
		(layers "F.Cu" "B.Cu")
		(net "GND")
	)
	(via
		(at 4.170426 -1.646428)
		(size 0.7112)
		(drill 0.4064)
		(layers "F.Cu" "B.Cu")
		(net "GND")
	)
	(via
		(at 156.464 -44.069)
		(size 0.7112)
		(drill 0.4064)
		(layers "F.Cu" "B.Cu")
		(net "GND")
	)
	(via
		(at 161.066226 -11.806428)
		(size 0.7112)
		(drill 0.4064)
		(layers "F.Cu" "B.Cu")
		(net "GND")
	)
	(via
		(at 155.168092 -108.060744)
		(size 0.7112)
		(drill 0.4064)
		(layers "F.Cu" "B.Cu")
		(net "GND")
	)
	(via
		(at 80.09382 -96.002856)
		(size 0.7112)
		(drill 0.4064)
		(layers "F.Cu" "B.Cu")
		(net "GND")
	)
	(via
		(at 63.220092 -9.127744)
		(size 0.7112)
		(drill 0.3556)
		(layers "F.Cu" "B.Cu")
		(net "GND")
	)
	(via
		(at 17.22882 -118.227856)
		(size 0.7112)
		(drill 0.4064)
		(layers "F.Cu" "B.Cu")
		(net "GND")
	)
	(via
		(at 112.9792 -50.165)
		(size 0.7112)
		(drill 0.4064)
		(layers "F.Cu" "B.Cu")
		(net "GND")
	)
	(via
		(at 138.297158 -53.438806)
		(size 0.7112)
		(drill 0.4064)
		(layers "F.Cu" "B.Cu")
		(net "GND")
	)
	(via
		(at 14.097 -105.918)
		(size 0.7112)
		(drill 0.4064)
		(layers "F.Cu" "B.Cu")
		(net "GND")
	)
	(via
		(at -0.748792 -76.759308)
		(size 0.7112)
		(drill 0.4064)
		(layers "F.Cu" "B.Cu")
		(net "GND")
	)
	(via
		(at 80.619092 -72.881744)
		(size 0.7112)
		(drill 0.4064)
		(layers "F.Cu" "B.Cu")
		(net "GND")
	)
	(via
		(at 50.139092 -57.641744)
		(size 0.7112)
		(drill 0.4064)
		(layers "F.Cu" "B.Cu")
		(net "GND")
	)
	(via
		(at 44.810426 -1.646428)
		(size 0.7112)
		(drill 0.4064)
		(layers "F.Cu" "B.Cu")
		(net "GND")
	)
	(via
		(at 126.339092 -57.641744)
		(size 0.7112)
		(drill 0.4064)
		(layers "F.Cu" "B.Cu")
		(net "GND")
	)
	(via
		(at 85.17382 -90.922856)
		(size 0.7112)
		(drill 0.4064)
		(layers "F.Cu" "B.Cu")
		(net "GND")
	)
	(via
		(at 75.539092 -57.641744)
		(size 0.7112)
		(drill 0.4064)
		(layers "F.Cu" "B.Cu")
		(net "GND")
	)
	(via
		(at 60.299092 -62.721744)
		(size 0.7112)
		(drill 0.4064)
		(layers "F.Cu" "B.Cu")
		(net "GND")
	)
	(via
		(at 33.528 -112.395)
		(size 0.7112)
		(drill 0.4064)
		(layers "F.Cu" "B.Cu")
		(net "GND")
	)
	(via
		(at 17.119092 -105.901744)
		(size 0.7112)
		(drill 0.3556)
		(layers "F.Cu" "B.Cu")
		(net "GND")
	)
	(via
		(at 114.046 -51.2318)
		(size 0.7112)
		(drill 0.4064)
		(layers "F.Cu" "B.Cu")
		(net "GND")
	)
	(via
		(at 60.299092 -52.434744)
		(size 0.7112)
		(drill 0.4064)
		(layers "F.Cu" "B.Cu")
		(net "GND")
	)
	(via
		(at 34.899092 -62.721744)
		(size 0.7112)
		(drill 0.4064)
		(layers "F.Cu" "B.Cu")
		(net "GND")
	)
	(via
		(at 132.054092 -118.220744)
		(size 0.7112)
		(drill 0.4064)
		(layers "F.Cu" "B.Cu")
		(net "GND")
	)
	(via
		(at 106.273092 -67.801744)
		(size 0.7112)
		(drill 0.4064)
		(layers "F.Cu" "B.Cu")
		(net "GND")
	)
	(via
		(at 110.850426 -1.646428)
		(size 0.7112)
		(drill 0.4064)
		(layers "F.Cu" "B.Cu")
		(net "GND")
	)
	(via
		(at 34.899092 -52.561744)
		(size 0.7112)
		(drill 0.4064)
		(layers "F.Cu" "B.Cu")
		(net "GND")
	)
	(via
		(at 161.066226 -1.646428)
		(size 0.7112)
		(drill 0.4064)
		(layers "F.Cu" "B.Cu")
		(net "GND")
	)
	(via
		(at 75.539092 -52.434744)
		(size 0.7112)
		(drill 0.4064)
		(layers "F.Cu" "B.Cu")
		(net "GND")
	)
	(via
		(at 106.2482 -50.165)
		(size 0.7112)
		(drill 0.4064)
		(layers "F.Cu" "B.Cu")
		(net "GND")
	)
	(via
		(at 132.984494 -50.960528)
		(size 0.7112)
		(drill 0.4064)
		(layers "F.Cu" "B.Cu")
		(net "GND")
	)
	(via
		(at 9.10082 -112.385856)
		(size 0.7112)
		(drill 0.4064)
		(layers "F.Cu" "B.Cu")
		(net "GND")
	)
	(via
		(at 127.572008 -50.898806)
		(size 0.7112)
		(drill 0.4064)
		(layers "F.Cu" "B.Cu")
		(net "GND")
	)
	(via
		(at 81.254092 -118.220744)
		(size 0.7112)
		(drill 0.4064)
		(layers "F.Cu" "B.Cu")
		(net "GND")
	)
	(via
		(at 70.459092 -57.641744)
		(size 0.7112)
		(drill 0.4064)
		(layers "F.Cu" "B.Cu")
		(net "GND")
	)
	(via
		(at 14.579092 -72.881744)
		(size 0.7112)
		(drill 0.4064)
		(layers "F.Cu" "B.Cu")
		(net "GND")
	)
	(via
		(at 49.784 -112.395)
		(size 0.7112)
		(drill 0.4064)
		(layers "F.Cu" "B.Cu")
		(net "GND")
	)
	(via
		(at 110.591092 -85.962744)
		(size 0.7112)
		(drill 0.4064)
		(layers "F.Cu" "B.Cu")
		(net "GND")
	)
	(via
		(at 160.973262 -16.688054)
		(size 0.7112)
		(drill 0.4064)
		(layers "F.Cu" "B.Cu")
		(net "GND")
	)
	(via
		(at 9.250426 -6.726428)
		(size 0.7112)
		(drill 0.4064)
		(layers "F.Cu" "B.Cu")
		(net "GND")
	)
	(via
		(at -0.660908 -65.261744)
		(size 0.7112)
		(drill 0.4064)
		(layers "F.Cu" "B.Cu")
		(net "GND")
	)
	(via
		(at 124.132594 -53.543708)
		(size 0.7112)
		(drill 0.4064)
		(layers "F.Cu" "B.Cu")
		(net "GND")
	)
	(via
		(at 54.970426 -6.726428)
		(size 0.7112)
		(drill 0.4064)
		(layers "F.Cu" "B.Cu")
		(net "GND")
	)
	(via
		(at 39.45382 -90.922856)
		(size 0.7112)
		(drill 0.4064)
		(layers "F.Cu" "B.Cu")
		(net "GND")
	)
	(via
		(at 110.591092 -91.042744)
		(size 0.7112)
		(drill 0.4064)
		(layers "F.Cu" "B.Cu")
		(net "GND")
	)
	(via
		(at 44.810426 -11.806428)
		(size 0.7112)
		(drill 0.4064)
		(layers "F.Cu" "B.Cu")
		(net "GND")
	)
	(via
		(at 65.130426 -6.726428)
		(size 0.7112)
		(drill 0.4064)
		(layers "F.Cu" "B.Cu")
		(net "GND")
	)
	(via
		(at 121.259092 -57.641744)
		(size 0.7112)
		(drill 0.4064)
		(layers "F.Cu" "B.Cu")
		(net "GND")
	)
	(via
		(at 80.370426 -1.646428)
		(size 0.7112)
		(drill 0.4064)
		(layers "F.Cu" "B.Cu")
		(net "GND")
	)
	(via
		(at 111.099092 -72.881744)
		(size 0.7112)
		(drill 0.4064)
		(layers "F.Cu" "B.Cu")
		(net "GND")
	)
	(via
		(at 118.4148 -50.165)
		(size 0.7112)
		(drill 0.4064)
		(layers "F.Cu" "B.Cu")
		(net "GND")
	)
	(via
		(at 29.565092 -67.801744)
		(size 0.7112)
		(drill 0.4064)
		(layers "F.Cu" "B.Cu")
		(net "GND")
	)
	(via
		(at 110.591092 -96.122744)
		(size 0.7112)
		(drill 0.4064)
		(layers "F.Cu" "B.Cu")
		(net "GND")
	)
	(via
		(at 45.059092 -57.641744)
		(size 0.7112)
		(drill 0.4064)
		(layers "F.Cu" "B.Cu")
		(net "GND")
	)
	(via
		(at 135.539226 -11.806428)
		(size 0.7112)
		(drill 0.4064)
		(layers "F.Cu" "B.Cu")
		(net "GND")
	)
	(via
		(at 19.659092 -52.561744)
		(size 0.7112)
		(drill 0.4064)
		(layers "F.Cu" "B.Cu")
		(net "GND")
	)
	(via
		(at 116.2812 -51.2318)
		(size 0.7112)
		(drill 0.4064)
		(layers "F.Cu" "B.Cu")
		(net "GND")
	)
	(via
		(at 70.967092 -72.881744)
		(size 0.7112)
		(drill 0.4064)
		(layers "F.Cu" "B.Cu")
		(net "GND")
	)
	(via
		(at 9.250426 -1.646428)
		(size 0.7112)
		(drill 0.4064)
		(layers "F.Cu" "B.Cu")
		(net "GND")
	)
	(via
		(at 135.539226 -6.726428)
		(size 0.7112)
		(drill 0.4064)
		(layers "F.Cu" "B.Cu")
		(net "GND")
	)
	(via
		(at 132.308092 -58.022744)
		(size 0.7112)
		(drill 0.4064)
		(layers "F.Cu" "B.Cu")
		(net "GND")
	)
	(via
		(at 75.01382 -96.002856)
		(size 0.7112)
		(drill 0.4064)
		(layers "F.Cu" "B.Cu")
		(net "GND")
	)
	(via
		(at 148.645626 -11.806428)
		(size 0.7112)
		(drill 0.4064)
		(layers "F.Cu" "B.Cu")
		(net "GND")
	)
	(via
		(at 128.879092 -49.894744)
		(size 0.7112)
		(drill 0.3556)
		(layers "F.Cu" "B.Cu")
		(net "GND")
	)
	(via
		(at 86.334092 -118.220744)
		(size 0.7112)
		(drill 0.4064)
		(layers "F.Cu" "B.Cu")
		(net "GND")
	)
	(via
		(at 24.739092 -62.721744)
		(size 0.7112)
		(drill 0.4064)
		(layers "F.Cu" "B.Cu")
		(net "GND")
	)
	(via
		(at 29.29382 -96.002856)
		(size 0.7112)
		(drill 0.4064)
		(layers "F.Cu" "B.Cu")
		(net "GND")
	)
	(via
		(at -0.660908 -60.181744)
		(size 0.7112)
		(drill 0.4064)
		(layers "F.Cu" "B.Cu")
		(net "GND")
	)
	(via
		(at 110.617 -50.165)
		(size 0.7112)
		(drill 0.4064)
		(layers "F.Cu" "B.Cu")
		(net "GND")
	)
	(via
		(at 64.85382 -96.002856)
		(size 0.7112)
		(drill 0.4064)
		(layers "F.Cu" "B.Cu")
		(net "GND")
	)
	(via
		(at 40.614092 -118.220744)
		(size 0.7112)
		(drill 0.4064)
		(layers "F.Cu" "B.Cu")
		(net "GND")
	)
	(via
		(at 70.06082 -112.385856)
		(size 0.7112)
		(drill 0.4064)
		(layers "F.Cu" "B.Cu")
		(net "GND")
	)
	(via
		(at 116.179092 -57.641744)
		(size 0.7112)
		(drill 0.4064)
		(layers "F.Cu" "B.Cu")
		(net "GND")
	)
	(via
		(at 100.690426 -1.646428)
		(size 0.7112)
		(drill 0.4064)
		(layers "F.Cu" "B.Cu")
		(net "GND")
	)
	(via
		(at 62.966092 -59.673744)
		(size 0.7112)
		(drill 0.3556)
		(layers "F.Cu" "B.Cu")
		(net "GND")
	)
	(via
		(at 29.29382 -106.162856)
		(size 0.7112)
		(drill 0.4064)
		(layers "F.Cu" "B.Cu")
		(net "GND")
	)
	(via
		(at 95.46082 -112.385856)
		(size 0.7112)
		(drill 0.4064)
		(layers "F.Cu" "B.Cu")
		(net "GND")
	)
	(via
		(at 69.93382 -90.922856)
		(size 0.7112)
		(drill 0.4064)
		(layers "F.Cu" "B.Cu")
		(net "GND")
	)
	(via
		(at 95.859092 -67.801744)
		(size 0.7112)
		(drill 0.4064)
		(layers "F.Cu" "B.Cu")
		(net "GND")
	)
	(via
		(at 121.259092 -67.801744)
		(size 0.7112)
		(drill 0.4064)
		(layers "F.Cu" "B.Cu")
		(net "GND")
	)
	(via
		(at 155.295092 -22.081744)
		(size 0.7112)
		(drill 0.4064)
		(layers "F.Cu" "B.Cu")
		(net "GND")
	)
	(via
		(at 105.770426 -6.726428)
		(size 0.7112)
		(drill 0.4064)
		(layers "F.Cu" "B.Cu")
		(net "GND")
	)
	(via
		(at 65.379092 -62.721744)
		(size 0.7112)
		(drill 0.4064)
		(layers "F.Cu" "B.Cu")
		(net "GND")
	)
	(via
		(at 100.41382 -106.162856)
		(size 0.7112)
		(drill 0.4064)
		(layers "F.Cu" "B.Cu")
		(net "GND")
	)
	(via
		(at -0.660908 -67.801744)
		(size 0.7112)
		(drill 0.4064)
		(layers "F.Cu" "B.Cu")
		(net "GND")
	)
	(via
		(at 123.065794 -52.476908)
		(size 0.7112)
		(drill 0.4064)
		(layers "F.Cu" "B.Cu")
		(net "GND")
	)
	(via
		(at 110.57382 -106.162856)
		(size 0.7112)
		(drill 0.4064)
		(layers "F.Cu" "B.Cu")
		(net "GND")
	)
	(via
		(at 29.845 -118.237)
		(size 0.7112)
		(drill 0.4064)
		(layers "F.Cu" "B.Cu")
		(net "GND")
	)
	(via
		(at 144.276826 -1.646428)
		(size 0.7112)
		(drill 0.4064)
		(layers "F.Cu" "B.Cu")
		(net "GND")
	)
	(via
		(at 156.311092 -67.674744)
		(size 0.7112)
		(drill 0.4064)
		(layers "F.Cu" "B.Cu")
		(net "GND")
	)
	(via
		(at 156.337 -50.546)
		(size 0.7112)
		(drill 0.4064)
		(layers "F.Cu" "B.Cu")
		(net "GND")
	)
	(via
		(at 90.779092 -52.434744)
		(size 0.7112)
		(drill 0.4064)
		(layers "F.Cu" "B.Cu")
		(net "GND")
	)
	(via
		(at 4.419092 -65.261744)
		(size 0.7112)
		(drill 0.4064)
		(layers "F.Cu" "B.Cu")
		(net "GND")
	)
	(via
		(at 39.979092 -52.561744)
		(size 0.7112)
		(drill 0.4064)
		(layers "F.Cu" "B.Cu")
		(net "GND")
	)
	(via
		(at 24.21382 -90.922856)
		(size 0.7112)
		(drill 0.4064)
		(layers "F.Cu" "B.Cu")
		(net "GND")
	)
	(via
		(at 75.290426 -6.726428)
		(size 0.7112)
		(drill 0.4064)
		(layers "F.Cu" "B.Cu")
		(net "GND")
	)
	(via
		(at 65.379092 -52.434744)
		(size 0.7112)
		(drill 0.4064)
		(layers "F.Cu" "B.Cu")
		(net "GND")
	)
	(via
		(at 92.811092 -9.127744)
		(size 0.7112)
		(drill 0.3556)
		(layers "F.Cu" "B.Cu")
		(net "GND")
	)
	(via
		(at 75.01382 -85.842856)
		(size 0.7112)
		(drill 0.4064)
		(layers "F.Cu" "B.Cu")
		(net "GND")
	)
	(via
		(at 44.53382 -106.162856)
		(size 0.7112)
		(drill 0.4064)
		(layers "F.Cu" "B.Cu")
		(net "GND")
	)
	(via
		(at 71.729092 -79.358744)
		(size 0.7112)
		(drill 0.3556)
		(layers "F.Cu" "B.Cu")
		(net "GND")
	)
	(via
		(at 115.671092 -85.962744)
		(size 0.7112)
		(drill 0.4064)
		(layers "F.Cu" "B.Cu")
		(net "GND")
	)
	(via
		(at 19.410426 -11.806428)
		(size 0.7112)
		(drill 0.4064)
		(layers "F.Cu" "B.Cu")
		(net "GND")
	)
	(via
		(at -0.660908 -55.101744)
		(size 0.7112)
		(drill 0.4064)
		(layers "F.Cu" "B.Cu")
		(net "GND")
	)
	(via
		(at 39.45382 -106.162856)
		(size 0.7112)
		(drill 0.4064)
		(layers "F.Cu" "B.Cu")
		(net "GND")
	)
	(via
		(at 76.174092 -118.220744)
		(size 0.7112)
		(drill 0.4064)
		(layers "F.Cu" "B.Cu")
		(net "GND")
	)
	(via
		(at 14.579092 -57.641744)
		(size 0.7112)
		(drill 0.4064)
		(layers "F.Cu" "B.Cu")
		(net "GND")
	)
	(via
		(at 153.014426 -11.806428)
		(size 0.7112)
		(drill 0.4064)
		(layers "F.Cu" "B.Cu")
		(net "GND")
	)
	(via
		(at 127.572008 -49.832006)
		(size 0.7112)
		(drill 0.4064)
		(layers "F.Cu" "B.Cu")
		(net "GND")
	)
	(via
		(at 1.879092 -72.881744)
		(size 0.7112)
		(drill 0.4064)
		(layers "F.Cu" "B.Cu")
		(net "GND")
	)
	(via
		(at 133.578092 -8.492744)
		(size 0.7112)
		(drill 0.3556)
		(layers "F.Cu" "B.Cu")
		(net "GND")
	)
	(via
		(at 137.230358 -53.438806)
		(size 0.7112)
		(drill 0.4064)
		(layers "F.Cu" "B.Cu")
		(net "GND")
	)
	(via
		(at 9.499092 -72.881744)
		(size 0.7112)
		(drill 0.4064)
		(layers "F.Cu" "B.Cu")
		(net "GND")
	)
	(via
		(at 125.199394 -53.543708)
		(size 0.7112)
		(drill 0.4064)
		(layers "F.Cu" "B.Cu")
		(net "GND")
	)
	(via
		(at 129.514092 -109.711744)
		(size 0.7112)
		(drill 0.3556)
		(layers "F.Cu" "B.Cu")
		(net "GND")
	)
	(via
		(at 8.632444 -92.184982)
		(size 0.7112)
		(drill 0.4064)
		(layers "F.Cu" "B.Cu")
		(net "GND")
	)
	(via
		(at 65.130426 -1.646428)
		(size 0.7112)
		(drill 0.4064)
		(layers "F.Cu" "B.Cu")
		(net "GND")
	)
	(via
		(at 92.557092 -109.457744)
		(size 0.7112)
		(drill 0.3556)
		(layers "F.Cu" "B.Cu")
		(net "GND")
	)
	(via
		(at 128.651 -77.597)
		(size 0.7112)
		(drill 0.4064)
		(layers "F.Cu" "B.Cu")
		(net "GND")
	)
	(via
		(at 49.890426 -1.646428)
		(size 0.7112)
		(drill 0.4064)
		(layers "F.Cu" "B.Cu")
		(net "GND")
	)
	(via
		(at 100.939092 -52.434744)
		(size 0.7112)
		(drill 0.4064)
		(layers "F.Cu" "B.Cu")
		(net "GND")
	)
	(via
		(at 95.859092 -62.721744)
		(size 0.7112)
		(drill 0.4064)
		(layers "F.Cu" "B.Cu")
		(net "GND")
	)
	(via
		(at 50.139092 -52.434744)
		(size 0.7112)
		(drill 0.4064)
		(layers "F.Cu" "B.Cu")
		(net "GND")
	)
	(via
		(at 120.751092 -91.042744)
		(size 0.7112)
		(drill 0.4064)
		(layers "F.Cu" "B.Cu")
		(net "GND")
	)
	(via
		(at 110.850426 -11.806428)
		(size 0.7112)
		(drill 0.4064)
		(layers "F.Cu" "B.Cu")
		(net "GND")
	)
	(via
		(at 160.756092 -118.093744)
		(size 0.7112)
		(drill 0.4064)
		(layers "F.Cu" "B.Cu")
		(net "GND")
	)
	(via
		(at 129.62509 -52.414678)
		(size 0.7112)
		(drill 0.4064)
		(layers "F.Cu" "B.Cu")
		(net "GND")
	)
	(via
		(at 60.050426 -6.726428)
		(size 0.7112)
		(drill 0.4064)
		(layers "F.Cu" "B.Cu")
		(net "GND")
	)
	(via
		(at -0.660908 -62.721744)
		(size 0.7112)
		(drill 0.4064)
		(layers "F.Cu" "B.Cu")
		(net "GND")
	)
	(via
		(at 19.786092 -85.962744)
		(size 0.7112)
		(drill 0.4064)
		(layers "F.Cu" "B.Cu")
		(net "GND")
	)
	(via
		(at 14.579092 -67.801744)
		(size 0.7112)
		(drill 0.4064)
		(layers "F.Cu" "B.Cu")
		(net "GND")
	)
	(via
		(at 39.979092 -67.801744)
		(size 0.7112)
		(drill 0.4064)
		(layers "F.Cu" "B.Cu")
		(net "GND")
	)
	(via
		(at 106.654092 -118.220744)
		(size 0.7112)
		(drill 0.4064)
		(layers "F.Cu" "B.Cu")
		(net "GND")
	)
	(via
		(at 60.299092 -57.641744)
		(size 0.7112)
		(drill 0.4064)
		(layers "F.Cu" "B.Cu")
		(net "GND")
	)
	(via
		(at 144.447514 -16.868902)
		(size 0.7112)
		(drill 0.3556)
		(layers "F.Cu" "B.Cu")
		(net "GND")
	)
	(via
		(at 59.77382 -85.842856)
		(size 0.7112)
		(drill 0.4064)
		(layers "F.Cu" "B.Cu")
		(net "GND")
	)
	(via
		(at 29.819092 -57.641744)
		(size 0.7112)
		(drill 0.4064)
		(layers "F.Cu" "B.Cu")
		(net "GND")
	)
	(via
		(at 131.170426 -11.806428)
		(size 0.7112)
		(drill 0.4064)
		(layers "F.Cu" "B.Cu")
		(net "GND")
	)
	(via
		(at 60.299092 -72.881744)
		(size 0.7112)
		(drill 0.4064)
		(layers "F.Cu" "B.Cu")
		(net "GND")
	)
	(via
		(at 130.175 -82.042)
		(size 0.7112)
		(drill 0.4064)
		(layers "F.Cu" "B.Cu")
		(net "GND")
	)
	(via
		(at 19.659092 -57.641744)
		(size 0.7112)
		(drill 0.4064)
		(layers "F.Cu" "B.Cu")
		(net "GND")
	)
	(via
		(at 116.179092 -72.881744)
		(size 0.7112)
		(drill 0.4064)
		(layers "F.Cu" "B.Cu")
		(net "GND")
	)
	(via
		(at 100.690426 -6.726428)
		(size 0.7112)
		(drill 0.4064)
		(layers "F.Cu" "B.Cu")
		(net "GND")
	)
	(via
		(at 1.879092 -62.721744)
		(size 0.7112)
		(drill 0.4064)
		(layers "F.Cu" "B.Cu")
		(net "GND")
	)
	(via
		(at 160.756092 -102.853744)
		(size 0.7112)
		(drill 0.4064)
		(layers "F.Cu" "B.Cu")
		(net "GND")
	)
	(via
		(at 4.170426 -6.726428)
		(size 0.7112)
		(drill 0.4064)
		(layers "F.Cu" "B.Cu")
		(net "GND")
	)
	(via
		(at 135.539226 -1.646428)
		(size 0.7112)
		(drill 0.4064)
		(layers "F.Cu" "B.Cu")
		(net "GND")
	)
	(via
		(at 115.930426 -11.806428)
		(size 0.7112)
		(drill 0.4064)
		(layers "F.Cu" "B.Cu")
		(net "GND")
	)
	(via
		(at 34.650426 -1.646428)
		(size 0.7112)
		(drill 0.4064)
		(layers "F.Cu" "B.Cu")
		(net "GND")
	)
	(via
		(at 121.998994 -53.543708)
		(size 0.7112)
		(drill 0.4064)
		(layers "F.Cu" "B.Cu")
		(net "GND")
	)
	(via
		(at 148.473922 -22.014434)
		(size 0.7112)
		(drill 0.4064)
		(layers "F.Cu" "B.Cu")
		(net "GND")
	)
	(via
		(at 100.41382 -96.002856)
		(size 0.7112)
		(drill 0.4064)
		(layers "F.Cu" "B.Cu")
		(net "GND")
	)
	(via
		(at 137.922 -50.165)
		(size 0.7112)
		(drill 0.3556)
		(layers "F.Cu" "B.Cu")
		(net "GND")
	)
	(via
		(at 101.574092 -118.220744)
		(size 0.7112)
		(drill 0.4064)
		(layers "F.Cu" "B.Cu")
		(net "GND")
	)
	(via
		(at 70.210426 -11.806428)
		(size 0.7112)
		(drill 0.4064)
		(layers "F.Cu" "B.Cu")
		(net "GND")
	)
	(via
		(at 24.739092 -72.881744)
		(size 0.7112)
		(drill 0.4064)
		(layers "F.Cu" "B.Cu")
		(net "GND")
	)
	(via
		(at 160.756092 -107.933744)
		(size 0.7112)
		(drill 0.4064)
		(layers "F.Cu" "B.Cu")
		(net "GND")
	)
	(via
		(at 123.065794 -53.543708)
		(size 0.7112)
		(drill 0.4064)
		(layers "F.Cu" "B.Cu")
		(net "GND")
	)
	(via
		(at 90.779092 -72.881744)
		(size 0.7112)
		(drill 0.4064)
		(layers "F.Cu" "B.Cu")
		(net "GND")
	)
	(via
		(at 115.671092 -96.122744)
		(size 0.7112)
		(drill 0.4064)
		(layers "F.Cu" "B.Cu")
		(net "GND")
	)
	(via
		(at 80.09382 -85.842856)
		(size 0.7112)
		(drill 0.4064)
		(layers "F.Cu" "B.Cu")
		(net "GND")
	)
	(via
		(at 75.290426 -11.806428)
		(size 0.7112)
		(drill 0.4064)
		(layers "F.Cu" "B.Cu")
		(net "GND")
	)
	(via
		(at 115.1128 -50.165)
		(size 0.7112)
		(drill 0.4064)
		(layers "F.Cu" "B.Cu")
		(net "GND")
	)
	(via
		(at 55.219092 -52.434744)
		(size 0.7112)
		(drill 0.4064)
		(layers "F.Cu" "B.Cu")
		(net "GND")
	)
	(via
		(at 105.770426 -11.806428)
		(size 0.7112)
		(drill 0.4064)
		(layers "F.Cu" "B.Cu")
		(net "GND")
	)
	(via
		(at 23.241 -118.237)
		(size 0.7112)
		(drill 0.4064)
		(layers "F.Cu" "B.Cu")
		(net "GND")
	)
	(via
		(at 19.659092 -72.881744)
		(size 0.7112)
		(drill 0.4064)
		(layers "F.Cu" "B.Cu")
		(net "GND")
	)
	(via
		(at 95.859092 -57.641744)
		(size 0.7112)
		(drill 0.4064)
		(layers "F.Cu" "B.Cu")
		(net "GND")
	)
	(via
		(at 39.37 -112.268)
		(size 0.7112)
		(drill 0.4064)
		(layers "F.Cu" "B.Cu")
		(net "GND")
	)
	(via
		(at 70.459092 -62.721744)
		(size 0.7112)
		(drill 0.4064)
		(layers "F.Cu" "B.Cu")
		(net "GND")
	)
	(via
		(at 128.55829 -52.414678)
		(size 0.7112)
		(drill 0.4064)
		(layers "F.Cu" "B.Cu")
		(net "GND")
	)
	(via
		(at 160.02 -87.757)
		(size 0.7112)
		(drill 0.4064)
		(layers "F.Cu" "B.Cu")
		(net "GND")
	)
	(via
		(at 60.050426 -1.646428)
		(size 0.7112)
		(drill 0.4064)
		(layers "F.Cu" "B.Cu")
		(net "GND")
	)
	(via
		(at 64.85382 -90.922856)
		(size 0.7112)
		(drill 0.4064)
		(layers "F.Cu" "B.Cu")
		(net "GND")
	)
	(via
		(at 142.238984 -71.874888)
		(size 0.7112)
		(drill 0.4064)
		(layers "F.Cu" "B.Cu")
		(net "GND")
	)
	(via
		(at 100.41382 -85.842856)
		(size 0.7112)
		(drill 0.4064)
		(layers "F.Cu" "B.Cu")
		(net "GND")
	)
	(via
		(at 115.78082 -112.385856)
		(size 0.7112)
		(drill 0.4064)
		(layers "F.Cu" "B.Cu")
		(net "GND")
	)
	(via
		(at 111.099092 -52.434744)
		(size 0.7112)
		(drill 0.4064)
		(layers "F.Cu" "B.Cu")
		(net "GND")
	)
	(via
		(at 109.5502 -50.165)
		(size 0.7112)
		(drill 0.4064)
		(layers "F.Cu" "B.Cu")
		(net "GND")
	)
	(via
		(at 15.722092 -91.169744)
		(size 0.7112)
		(drill 0.4064)
		(layers "F.Cu" "B.Cu")
		(net "GND")
	)
	(via
		(at 19.177 -106.045)
		(size 0.7112)
		(drill 0.4064)
		(layers "F.Cu" "B.Cu")
		(net "GND")
	)
	(via
		(at 5.054092 -118.220744)
		(size 0.7112)
		(drill 0.4064)
		(layers "F.Cu" "B.Cu")
		(net "GND")
	)
	(via
		(at 4.419092 -52.561744)
		(size 0.7112)
		(drill 0.4064)
		(layers "F.Cu" "B.Cu")
		(net "GND")
	)
	(via
		(at 45.059092 -72.881744)
		(size 0.7112)
		(drill 0.4064)
		(layers "F.Cu" "B.Cu")
		(net "GND")
	)
	(via
		(at 114.046 -50.165)
		(size 0.7112)
		(drill 0.4064)
		(layers "F.Cu" "B.Cu")
		(net "GND")
	)
	(via
		(at 9.499092 -67.801744)
		(size 0.7112)
		(drill 0.4064)
		(layers "F.Cu" "B.Cu")
		(net "GND")
	)
	(via
		(at -1.676908 -90.729308)
		(size 0.7112)
		(drill 0.4064)
		(layers "F.Cu" "B.Cu")
		(net "GND")
	)
	(via
		(at 118.4148 -51.2318)
		(size 0.7112)
		(drill 0.4064)
		(layers "F.Cu" "B.Cu")
		(net "GND")
	)
	(via
		(at 6.35 -87.122)
		(size 0.7112)
		(drill 0.4064)
		(layers "F.Cu" "B.Cu")
		(net "GND")
	)
	(via
		(at 75.01382 -106.162856)
		(size 0.7112)
		(drill 0.4064)
		(layers "F.Cu" "B.Cu")
		(net "GND")
	)
	(via
		(at 44.53382 -90.922856)
		(size 0.7112)
		(drill 0.4064)
		(layers "F.Cu" "B.Cu")
		(net "GND")
	)
	(via
		(at 108.3818 -51.2318)
		(size 0.7112)
		(drill 0.4064)
		(layers "F.Cu" "B.Cu")
		(net "GND")
	)
	(via
		(at 85.17382 -106.162856)
		(size 0.7112)
		(drill 0.4064)
		(layers "F.Cu" "B.Cu")
		(net "GND")
	)
	(via
		(at 54.69382 -85.842856)
		(size 0.7112)
		(drill 0.4064)
		(layers "F.Cu" "B.Cu")
		(net "GND")
	)
	(via
		(at 132.984494 -49.893728)
		(size 0.7112)
		(drill 0.4064)
		(layers "F.Cu" "B.Cu")
		(net "GND")
	)
	(via
		(at 120.751092 -85.962744)
		(size 0.7112)
		(drill 0.4064)
		(layers "F.Cu" "B.Cu")
		(net "GND")
	)
	(via
		(at 148.645626 -6.726428)
		(size 0.7112)
		(drill 0.4064)
		(layers "F.Cu" "B.Cu")
		(net "GND")
	)
	(via
		(at 100.081588 -78.298548)
		(size 0.7112)
		(drill 0.3556)
		(layers "F.Cu" "B.Cu")
		(net "GND")
	)
	(via
		(at 121.010426 -11.806428)
		(size 0.7112)
		(drill 0.4064)
		(layers "F.Cu" "B.Cu")
		(net "GND")
	)
	(via
		(at 121.158 -106.172)
		(size 0.7112)
		(drill 0.4064)
		(layers "F.Cu" "B.Cu")
		(net "GND")
	)
	(via
		(at 132.176774 -76.392278)
		(size 0.7112)
		(drill 0.4064)
		(layers "F.Cu" "B.Cu")
		(net "GND")
	)
	(via
		(at 152.4 -75.819)
		(size 0.7112)
		(drill 0.4064)
		(layers "F.Cu" "B.Cu")
		(net "GND")
	)
	(via
		(at 49.890426 -11.806428)
		(size 0.7112)
		(drill 0.4064)
		(layers "F.Cu" "B.Cu")
		(net "GND")
	)
	(via
		(at 85.17382 -96.002856)
		(size 0.7112)
		(drill 0.4064)
		(layers "F.Cu" "B.Cu")
		(net "GND")
	)
	(via
		(at 105.62082 -112.385856)
		(size 0.7112)
		(drill 0.4064)
		(layers "F.Cu" "B.Cu")
		(net "GND")
	)
	(via
		(at 160.756092 -113.013744)
		(size 0.7112)
		(drill 0.4064)
		(layers "F.Cu" "B.Cu")
		(net "GND")
	)
	(via
		(at 131.75869 -52.414678)
		(size 0.7112)
		(drill 0.4064)
		(layers "F.Cu" "B.Cu")
		(net "GND")
	)
	(via
		(at 155.168092 -113.140744)
		(size 0.7112)
		(drill 0.4064)
		(layers "F.Cu" "B.Cu")
		(net "GND")
	)
	(via
		(at 125.199394 -52.476908)
		(size 0.7112)
		(drill 0.4064)
		(layers "F.Cu" "B.Cu")
		(net "GND")
	)
	(via
		(at 29.29382 -85.842856)
		(size 0.7112)
		(drill 0.4064)
		(layers "F.Cu" "B.Cu")
		(net "GND")
	)
	(via
		(at 149.225 -80.899)
		(size 0.7112)
		(drill 0.4064)
		(layers "F.Cu" "B.Cu")
		(net "GND")
	)
	(via
		(at -1.676908 -88.189308)
		(size 0.7112)
		(drill 0.4064)
		(layers "F.Cu" "B.Cu")
		(net "GND")
	)
	(via
		(at 34.37382 -96.002856)
		(size 0.7112)
		(drill 0.4064)
		(layers "F.Cu" "B.Cu")
		(net "GND")
	)
	(via
		(at 29.29382 -90.922856)
		(size 0.7112)
		(drill 0.4064)
		(layers "F.Cu" "B.Cu")
		(net "GND")
	)
	(via
		(at 95.859092 -72.881744)
		(size 0.7112)
		(drill 0.4064)
		(layers "F.Cu" "B.Cu")
		(net "GND")
	)
	(via
		(at 5.588 -98.425)
		(size 0.7112)
		(drill 0.4064)
		(layers "F.Cu" "B.Cu")
		(net "GND")
	)
	(via
		(at 142.621 -75.692)
		(size 0.7112)
		(drill 0.4064)
		(layers "F.Cu" "B.Cu")
		(net "GND")
	)
	(via
		(at 85.30082 -112.385856)
		(size 0.7112)
		(drill 0.4064)
		(layers "F.Cu" "B.Cu")
		(net "GND")
	)
	(via
		(at 80.619092 -57.641744)
		(size 0.7112)
		(drill 0.4064)
		(layers "F.Cu" "B.Cu")
		(net "GND")
	)
	(via
		(at 24.485092 -85.835744)
		(size 0.7112)
		(drill 0.4064)
		(layers "F.Cu" "B.Cu")
		(net "GND")
	)
	(via
		(at 156.464 -29.337)
		(size 0.7112)
		(drill 0.4064)
		(layers "F.Cu" "B.Cu")
		(net "GND")
	)
	(via
		(at 64.98082 -112.385856)
		(size 0.7112)
		(drill 0.4064)
		(layers "F.Cu" "B.Cu")
		(net "GND")
	)
	(via
		(at 85.17382 -85.842856)
		(size 0.7112)
		(drill 0.4064)
		(layers "F.Cu" "B.Cu")
		(net "GND")
	)
	(via
		(at 14.579092 -62.721744)
		(size 0.7112)
		(drill 0.4064)
		(layers "F.Cu" "B.Cu")
		(net "GND")
	)
	(via
		(at 55.219092 -57.641744)
		(size 0.7112)
		(drill 0.4064)
		(layers "F.Cu" "B.Cu")
		(net "GND")
	)
	(via
		(at 21.945092 -77.199744)
		(size 0.7112)
		(drill 0.4064)
		(layers "F.Cu" "B.Cu")
		(net "GND")
	)
	(via
		(at 6.477 -89.662)
		(size 0.7112)
		(drill 0.4064)
		(layers "F.Cu" "B.Cu")
		(net "GND")
	)
	(via
		(at 130.69189 -52.414678)
		(size 0.7112)
		(drill 0.4064)
		(layers "F.Cu" "B.Cu")
		(net "GND")
	)
	(via
		(at 29.057092 -78.469744)
		(size 0.7112)
		(drill 0.3556)
		(layers "F.Cu" "B.Cu")
		(net "GND")
	)
	(via
		(at 45.059092 -52.434744)
		(size 0.7112)
		(drill 0.4064)
		(layers "F.Cu" "B.Cu")
		(net "GND")
	)
	(via
		(at 44.577 -112.268)
		(size 0.7112)
		(drill 0.4064)
		(layers "F.Cu" "B.Cu")
		(net "GND")
	)
	(via
		(at 131.170426 -1.646428)
		(size 0.7112)
		(drill 0.4064)
		(layers "F.Cu" "B.Cu")
		(net "GND")
	)
	(via
		(at 45.694092 -118.220744)
		(size 0.7112)
		(drill 0.4064)
		(layers "F.Cu" "B.Cu")
		(net "GND")
	)
	(via
		(at 29.819092 -52.561744)
		(size 0.7112)
		(drill 0.4064)
		(layers "F.Cu" "B.Cu")
		(net "GND")
	)
	(via
		(at 100.690426 -11.806428)
		(size 0.7112)
		(drill 0.4064)
		(layers "F.Cu" "B.Cu")
		(net "GND")
	)
	(via
		(at 75.14082 -112.385856)
		(size 0.7112)
		(drill 0.4064)
		(layers "F.Cu" "B.Cu")
		(net "GND")
	)
	(via
		(at 26.75382 -112.512856)
		(size 0.7112)
		(drill 0.4064)
		(layers "F.Cu" "B.Cu")
		(net "GND")
	)
	(via
		(at 85.699092 -62.721744)
		(size 0.7112)
		(drill 0.4064)
		(layers "F.Cu" "B.Cu")
		(net "GND")
	)
	(via
		(at 111.6838 -51.2318)
		(size 0.7112)
		(drill 0.4064)
		(layers "F.Cu" "B.Cu")
		(net "GND")
	)
	(via
		(at 95.610426 -6.726428)
		(size 0.7112)
		(drill 0.4064)
		(layers "F.Cu" "B.Cu")
		(net "GND")
	)
	(via
		(at 35.534092 -118.220744)
		(size 0.7112)
		(drill 0.4064)
		(layers "F.Cu" "B.Cu")
		(net "GND")
	)
	(via
		(at 106.2482 -51.2318)
		(size 0.7112)
		(drill 0.4064)
		(layers "F.Cu" "B.Cu")
		(net "GND")
	)
	(via
		(at 1.879092 -57.641744)
		(size 0.7112)
		(drill 0.4064)
		(layers "F.Cu" "B.Cu")
		(net "GND")
	)
	(via
		(at 134.051294 -49.893728)
		(size 0.7112)
		(drill 0.4064)
		(layers "F.Cu" "B.Cu")
		(net "GND")
	)
	(via
		(at 85.699092 -52.434744)
		(size 0.7112)
		(drill 0.4064)
		(layers "F.Cu" "B.Cu")
		(net "GND")
	)
	(via
		(at 153.014426 -1.646428)
		(size 0.7112)
		(drill 0.4064)
		(layers "F.Cu" "B.Cu")
		(net "GND")
	)
	(via
		(at 123.31954 -112.42548)
		(size 0.7112)
		(drill 0.4064)
		(layers "F.Cu" "B.Cu")
		(net "GND")
	)
	(via
		(at 80.370426 -6.726428)
		(size 0.7112)
		(drill 0.4064)
		(layers "F.Cu" "B.Cu")
		(net "GND")
	)
	(via
		(at 65.379092 -72.881744)
		(size 0.7112)
		(drill 0.4064)
		(layers "F.Cu" "B.Cu")
		(net "GND")
	)
	(via
		(at 138.8364 -65.524634)
		(size 0.7112)
		(drill 0.4064)
		(layers "F.Cu" "B.Cu")
		(net "GND")
	)
	(via
		(at 15.849092 -85.962744)
		(size 0.7112)
		(drill 0.4064)
		(layers "F.Cu" "B.Cu")
		(net "GND")
	)
	(via
		(at -1.76276 -80.326738)
		(size 0.7112)
		(drill 0.4064)
		(layers "F.Cu" "B.Cu")
		(net "GND")
	)
	(via
		(at 136.432544 -82.906108)
		(size 0.7112)
		(drill 0.4064)
		(layers "F.Cu" "B.Cu")
		(net "GND")
	)
	(via
		(at 90.530426 -6.726428)
		(size 0.7112)
		(drill 0.4064)
		(layers "F.Cu" "B.Cu")
		(net "GND")
	)
	(via
		(at 64.85382 -106.162856)
		(size 0.7112)
		(drill 0.4064)
		(layers "F.Cu" "B.Cu")
		(net "GND")
	)
	(via
		(at 115.1128 -51.2318)
		(size 0.7112)
		(drill 0.4064)
		(layers "F.Cu" "B.Cu")
		(net "GND")
	)
	(via
		(at 121.180098 -50.030888)
		(size 0.7112)
		(drill 0.4064)
		(layers "F.Cu" "B.Cu")
		(net "GND")
	)
	(via
		(at 156.311092 -72.246744)
		(size 0.7112)
		(drill 0.4064)
		(layers "F.Cu" "B.Cu")
		(net "GND")
	)
	(via
		(at 55.219092 -67.801744)
		(size 0.7112)
		(drill 0.4064)
		(layers "F.Cu" "B.Cu")
		(net "GND")
	)
	(via
		(at 129.62509 -53.481478)
		(size 0.7112)
		(drill 0.4064)
		(layers "F.Cu" "B.Cu")
		(net "GND")
	)
	(via
		(at 126.090426 -11.806428)
		(size 0.7112)
		(drill 0.4064)
		(layers "F.Cu" "B.Cu")
		(net "GND")
	)
	(via
		(at 137.230358 -52.372006)
		(size 0.7112)
		(drill 0.4064)
		(layers "F.Cu" "B.Cu")
		(net "GND")
	)
	(via
		(at 126.505208 -49.832006)
		(size 0.7112)
		(drill 0.4064)
		(layers "F.Cu" "B.Cu")
		(net "GND")
	)
	(via
		(at 115.65382 -106.162856)
		(size 0.7112)
		(drill 0.4064)
		(layers "F.Cu" "B.Cu")
		(net "GND")
	)
	(via
		(at 80.370426 -11.806428)
		(size 0.7112)
		(drill 0.4064)
		(layers "F.Cu" "B.Cu")
		(net "GND")
	)
	(via
		(at 9.499092 -52.561744)
		(size 0.7112)
		(drill 0.4064)
		(layers "F.Cu" "B.Cu")
		(net "GND")
	)
	(via
		(at 5.588 -95.123)
		(size 0.7112)
		(drill 0.4064)
		(layers "F.Cu" "B.Cu")
		(net "GND")
	)
	(via
		(at 111.099092 -67.801744)
		(size 0.7112)
		(drill 0.4064)
		(layers "F.Cu" "B.Cu")
		(net "GND")
	)
	(via
		(at 111.734092 -118.220744)
		(size 0.7112)
		(drill 0.4064)
		(layers "F.Cu" "B.Cu")
		(net "GND")
	)
	(via
		(at 19.913092 -91.042744)
		(size 0.7112)
		(drill 0.4064)
		(layers "F.Cu" "B.Cu")
		(net "GND")
	)
	(via
		(at 1.625092 -93.963744)
		(size 0.7112)
		(drill 0.4064)
		(layers "F.Cu" "B.Cu")
		(net "GND")
	)
	(via
		(at 90.779092 -67.801744)
		(size 0.7112)
		(drill 0.4064)
		(layers "F.Cu" "B.Cu")
		(net "GND")
	)
	(via
		(at 138.297158 -52.372006)
		(size 0.7112)
		(drill 0.4064)
		(layers "F.Cu" "B.Cu")
		(net "GND")
	)
	(via
		(at 44.53382 -85.842856)
		(size 0.7112)
		(drill 0.4064)
		(layers "F.Cu" "B.Cu")
		(net "GND")
	)
	(via
		(at 6.959092 -55.101744)
		(size 0.7112)
		(drill 0.4064)
		(layers "F.Cu" "B.Cu")
		(net "GND")
	)
	(via
		(at 119.137684 -112.69599)
		(size 0.7112)
		(drill 0.3556)
		(layers "F.Cu" "B.Cu")
		(net "GND")
	)
	(via
		(at 14.579092 -52.561744)
		(size 0.7112)
		(drill 0.4064)
		(layers "F.Cu" "B.Cu")
		(net "GND")
	)
	(via
		(at 1.752092 -118.220744)
		(size 0.7112)
		(drill 0.4064)
		(layers "F.Cu" "B.Cu")
		(net "GND")
	)
	(via
		(at 90.779092 -62.721744)
		(size 0.7112)
		(drill 0.4064)
		(layers "F.Cu" "B.Cu")
		(net "GND")
	)
	(via
		(at 39.45382 -96.002856)
		(size 0.7112)
		(drill 0.4064)
		(layers "F.Cu" "B.Cu")
		(net "GND")
	)
	(via
		(at 128.55829 -53.481478)
		(size 0.7112)
		(drill 0.4064)
		(layers "F.Cu" "B.Cu")
		(net "GND")
	)
	(via
		(at 1.879092 -70.341744)
		(size 0.7112)
		(drill 0.4064)
		(layers "F.Cu" "B.Cu")
		(net "GND")
	)
	(via
		(at 107.315 -50.165)
		(size 0.7112)
		(drill 0.4064)
		(layers "F.Cu" "B.Cu")
		(net "GND")
	)
	(via
		(at 24.739092 -67.801744)
		(size 0.7112)
		(drill 0.4064)
		(layers "F.Cu" "B.Cu")
		(net "GND")
	)
	(via
		(at 85.699092 -67.801744)
		(size 0.7112)
		(drill 0.4064)
		(layers "F.Cu" "B.Cu")
		(net "GND")
	)
	(via
		(at 139.908026 -6.726428)
		(size 0.7112)
		(drill 0.4064)
		(layers "F.Cu" "B.Cu")
		(net "GND")
	)
	(via
		(at 121.998994 -52.476908)
		(size 0.7112)
		(drill 0.4064)
		(layers "F.Cu" "B.Cu")
		(net "GND")
	)
	(via
		(at 95.610426 -1.646428)
		(size 0.7112)
		(drill 0.4064)
		(layers "F.Cu" "B.Cu")
		(net "GND")
	)
	(via
		(at 69.93382 -85.842856)
		(size 0.7112)
		(drill 0.4064)
		(layers "F.Cu" "B.Cu")
		(net "GND")
	)
	(via
		(at 110.70082 -112.385856)
		(size 0.7112)
		(drill 0.4064)
		(layers "F.Cu" "B.Cu")
		(net "GND")
	)
	(via
		(at 148.645626 -1.646428)
		(size 0.7112)
		(drill 0.4064)
		(layers "F.Cu" "B.Cu")
		(net "GND")
	)
	(via
		(at 100.939092 -72.881744)
		(size 0.7112)
		(drill 0.4064)
		(layers "F.Cu" "B.Cu")
		(net "GND")
	)
	(via
		(at 6.959092 -70.341744)
		(size 0.7112)
		(drill 0.4064)
		(layers "F.Cu" "B.Cu")
		(net "GND")
	)
	(via
		(at -0.660908 -57.641744)
		(size 0.7112)
		(drill 0.4064)
		(layers "F.Cu" "B.Cu")
		(net "GND")
	)
	(via
		(at 60.050426 -11.806428)
		(size 0.7112)
		(drill 0.4064)
		(layers "F.Cu" "B.Cu")
		(net "GND")
	)
	(via
		(at 49.61382 -96.002856)
		(size 0.7112)
		(drill 0.4064)
		(layers "F.Cu" "B.Cu")
		(net "GND")
	)
	(via
		(at -1.803908 -83.109308)
		(size 0.7112)
		(drill 0.4064)
		(layers "F.Cu" "B.Cu")
		(net "GND")
	)
	(via
		(at 16.357092 -77.326744)
		(size 0.7112)
		(drill 0.4064)
		(layers "F.Cu" "B.Cu")
		(net "GND")
	)
	(via
		(at 34.37382 -85.842856)
		(size 0.7112)
		(drill 0.4064)
		(layers "F.Cu" "B.Cu")
		(net "GND")
	)
	(via
		(at 95.33382 -96.002856)
		(size 0.7112)
		(drill 0.4064)
		(layers "F.Cu" "B.Cu")
		(net "GND")
	)
	(via
		(at 12.039092 -54.593744)
		(size 0.7112)
		(drill 0.3556)
		(layers "F.Cu" "B.Cu")
		(net "GND")
	)
	(via
		(at 121.894092 -118.220744)
		(size 0.7112)
		(drill 0.4064)
		(layers "F.Cu" "B.Cu")
		(net "GND")
	)
	(via
		(at 160.883092 -82.660744)
		(size 0.7112)
		(drill 0.4064)
		(layers "F.Cu" "B.Cu")
		(net "GND")
	)
	(via
		(at 19.913092 -94.471744)
		(size 0.7112)
		(drill 0.3556)
		(layers "F.Cu" "B.Cu")
		(net "GND")
	)
	(via
		(at 161.066226 -6.726428)
		(size 0.7112)
		(drill 0.4064)
		(layers "F.Cu" "B.Cu")
		(net "GND")
	)
	(via
		(at 156.590492 -80.323944)
		(size 0.7112)
		(drill 0.4064)
		(layers "F.Cu" "B.Cu")
		(net "GND")
	)
	(via
		(at 140.505434 -51.022758)
		(size 0.7112)
		(drill 0.4064)
		(layers "F.Cu" "B.Cu")
		(net "GND")
	)
	(via
		(at 64.85382 -85.842856)
		(size 0.7112)
		(drill 0.4064)
		(layers "F.Cu" "B.Cu")
		(net "GND")
	)
	(via
		(at 90.38082 -112.385856)
		(size 0.7112)
		(drill 0.4064)
		(layers "F.Cu" "B.Cu")
		(net "GND")
	)
	(via
		(at 29.570426 -11.806428)
		(size 0.7112)
		(drill 0.4064)
		(layers "F.Cu" "B.Cu")
		(net "GND")
	)
	(via
		(at 116.179092 -67.801744)
		(size 0.7112)
		(drill 0.4064)
		(layers "F.Cu" "B.Cu")
		(net "GND")
	)
	(via
		(at 39.730426 -6.726428)
		(size 0.7112)
		(drill 0.4064)
		(layers "F.Cu" "B.Cu")
		(net "GND")
	)
	(via
		(at 39.979092 -57.641744)
		(size 0.7112)
		(drill 0.4064)
		(layers "F.Cu" "B.Cu")
		(net "GND")
	)
	(via
		(at 19.659092 -67.801744)
		(size 0.7112)
		(drill 0.4064)
		(layers "F.Cu" "B.Cu")
		(net "GND")
	)
	(via
		(at 55.854092 -118.220744)
		(size 0.7112)
		(drill 0.4064)
		(layers "F.Cu" "B.Cu")
		(net "GND")
	)
	(via
		(at 65.130426 -11.806428)
		(size 0.7112)
		(drill 0.4064)
		(layers "F.Cu" "B.Cu")
		(net "GND")
	)
	(via
		(at 156.464 -35.052)
		(size 0.7112)
		(drill 0.4064)
		(layers "F.Cu" "B.Cu")
		(net "GND")
	)
	(via
		(at 105.49382 -106.162856)
		(size 0.7112)
		(drill 0.4064)
		(layers "F.Cu" "B.Cu")
		(net "GND")
	)
	(via
		(at 144.276826 -11.806428)
		(size 0.7112)
		(drill 0.4064)
		(layers "F.Cu" "B.Cu")
		(net "GND")
	)
	(via
		(at 1.879092 -55.101744)
		(size 0.7112)
		(drill 0.4064)
		(layers "F.Cu" "B.Cu")
		(net "GND")
	)
	(via
		(at 137.388092 -58.022744)
		(size 0.7112)
		(drill 0.4064)
		(layers "F.Cu" "B.Cu")
		(net "GND")
	)
	(via
		(at 125.831092 -91.042744)
		(size 0.7112)
		(drill 0.4064)
		(layers "F.Cu" "B.Cu")
		(net "GND")
	)
	(via
		(at 80.09382 -106.162856)
		(size 0.7112)
		(drill 0.4064)
		(layers "F.Cu" "B.Cu")
		(net "GND")
	)
	(via
		(at -1.803908 -85.649308)
		(size 0.7112)
		(drill 0.4064)
		(layers "F.Cu" "B.Cu")
		(net "GND")
	)
	(via
		(at 116.179092 -62.721744)
		(size 0.7112)
		(drill 0.4064)
		(layers "F.Cu" "B.Cu")
		(net "GND")
	)
	(via
		(at 126.505208 -50.898806)
		(size 0.7112)
		(drill 0.4064)
		(layers "F.Cu" "B.Cu")
		(net "GND")
	)
	(via
		(at 100.939092 -67.801744)
		(size 0.7112)
		(drill 0.4064)
		(layers "F.Cu" "B.Cu")
		(net "GND")
	)
	(via
		(at 108.3818 -50.165)
		(size 0.7112)
		(drill 0.4064)
		(layers "F.Cu" "B.Cu")
		(net "GND")
	)
	(via
		(at 19.659092 -62.721744)
		(size 0.7112)
		(drill 0.4064)
		(layers "F.Cu" "B.Cu")
		(net "GND")
	)
	(via
		(at 60.934092 -118.220744)
		(size 0.7112)
		(drill 0.4064)
		(layers "F.Cu" "B.Cu")
		(net "GND")
	)
	(via
		(at 50.139092 -72.881744)
		(size 0.7112)
		(drill 0.4064)
		(layers "F.Cu" "B.Cu")
		(net "GND")
	)
	(via
		(at 156.438092 -57.006744)
		(size 0.7112)
		(drill 0.4064)
		(layers "F.Cu" "B.Cu")
		(net "GND")
	)
	(via
		(at 116.814092 -118.220744)
		(size 0.7112)
		(drill 0.4064)
		(layers "F.Cu" "B.Cu")
		(net "GND")
	)
	(via
		(at 6.959092 -65.261744)
		(size 0.7112)
		(drill 0.4064)
		(layers "F.Cu" "B.Cu")
		(net "GND")
	)
	(via
		(at 1.879092 -67.801744)
		(size 0.7112)
		(drill 0.4064)
		(layers "F.Cu" "B.Cu")
		(net "GND")
	)
	(via
		(at 90.25382 -106.162856)
		(size 0.7112)
		(drill 0.4064)
		(layers "F.Cu" "B.Cu")
		(net "GND")
	)
	(via
		(at 70.459092 -52.434744)
		(size 0.7112)
		(drill 0.4064)
		(layers "F.Cu" "B.Cu")
		(net "GND")
	)
	(via
		(at 66.014092 -118.220744)
		(size 0.7112)
		(drill 0.4064)
		(layers "F.Cu" "B.Cu")
		(net "GND")
	)
	(via
		(at 75.290426 -1.646428)
		(size 0.7112)
		(drill 0.4064)
		(layers "F.Cu" "B.Cu")
		(net "GND")
	)
	(via
		(at 110.617 -51.2318)
		(size 0.7112)
		(drill 0.4064)
		(layers "F.Cu" "B.Cu")
		(net "GND")
	)
	(via
		(at 140.505434 -49.955958)
		(size 0.7112)
		(drill 0.4064)
		(layers "F.Cu" "B.Cu")
		(net "GND")
	)
	(via
		(at 146.685 -77.47)
		(size 0.7112)
		(drill 0.4064)
		(layers "F.Cu" "B.Cu")
		(net "GND")
	)
	(via
		(at 157.383226 -6.726428)
		(size 0.7112)
		(drill 0.4064)
		(layers "F.Cu" "B.Cu")
		(net "GND")
	)
	(via
		(at 24.739092 -52.561744)
		(size 0.7112)
		(drill 0.4064)
		(layers "F.Cu" "B.Cu")
		(net "GND")
	)
	(via
		(at 117.348 -50.165)
		(size 0.7112)
		(drill 0.4064)
		(layers "F.Cu" "B.Cu")
		(net "GND")
	)
	(via
		(at 139.908026 -1.646428)
		(size 0.7112)
		(drill 0.4064)
		(layers "F.Cu" "B.Cu")
		(net "GND")
	)
	(via
		(at 80.22082 -112.385856)
		(size 0.7112)
		(drill 0.4064)
		(layers "F.Cu" "B.Cu")
		(net "GND")
	)
	(via
		(at 136.163558 -53.438806)
		(size 0.7112)
		(drill 0.4064)
		(layers "F.Cu" "B.Cu")
		(net "GND")
	)
	(via
		(at 6.959092 -52.561744)
		(size 0.7112)
		(drill 0.4064)
		(layers "F.Cu" "B.Cu")
		(net "GND")
	)
	(via
		(at 85.450426 -1.646428)
		(size 0.7112)
		(drill 0.4064)
		(layers "F.Cu" "B.Cu")
		(net "GND")
	)
	(via
		(at 39.730426 -1.646428)
		(size 0.7112)
		(drill 0.4064)
		(layers "F.Cu" "B.Cu")
		(net "GND")
	)
	(via
		(at 116.2812 -50.165)
		(size 0.7112)
		(drill 0.4064)
		(layers "F.Cu" "B.Cu")
		(net "GND")
	)
	(via
		(at -0.660908 -70.341744)
		(size 0.7112)
		(drill 0.4064)
		(layers "F.Cu" "B.Cu")
		(net "GND")
	)
	(via
		(at 4.419092 -55.101744)
		(size 0.7112)
		(drill 0.4064)
		(layers "F.Cu" "B.Cu")
		(net "GND")
	)
	(via
		(at 95.859092 -52.434744)
		(size 0.7112)
		(drill 0.4064)
		(layers "F.Cu" "B.Cu")
		(net "GND")
	)
	(via
		(at 139.573 -77.597)
		(size 0.7112)
		(drill 0.4064)
		(layers "F.Cu" "B.Cu")
		(net "GND")
	)
	(via
		(at 120.751092 -96.122744)
		(size 0.7112)
		(drill 0.4064)
		(layers "F.Cu" "B.Cu")
		(net "GND")
	)
	(via
		(at 54.69382 -106.162856)
		(size 0.7112)
		(drill 0.4064)
		(layers "F.Cu" "B.Cu")
		(net "GND")
	)
	(via
		(at 19.304 -8.128)
		(size 0.7112)
		(drill 0.3556)
		(layers "F.Cu" "B.Cu")
		(net "GND")
	)
	(via
		(at 39.979092 -72.881744)
		(size 0.7112)
		(drill 0.4064)
		(layers "F.Cu" "B.Cu")
		(net "GND")
	)
	(via
		(at 9.339326 -62.721744)
		(size 0.7112)
		(drill 0.4064)
		(layers "F.Cu" "B.Cu")
		(net "GND")
	)
	(via
		(at 49.61382 -85.842856)
		(size 0.7112)
		(drill 0.4064)
		(layers "F.Cu" "B.Cu")
		(net "GND")
	)
	(via
		(at 156.438092 -62.086744)
		(size 0.7112)
		(drill 0.4064)
		(layers "F.Cu" "B.Cu")
		(net "GND")
	)
	(via
		(at 155.168092 -118.220744)
		(size 0.7112)
		(drill 0.4064)
		(layers "F.Cu" "B.Cu")
		(net "GND")
	)
	(via
		(at 59.77382 -90.922856)
		(size 0.7112)
		(drill 0.4064)
		(layers "F.Cu" "B.Cu")
		(net "GND")
	)
	(via
		(at 39.45382 -85.842856)
		(size 0.7112)
		(drill 0.4064)
		(layers "F.Cu" "B.Cu")
		(net "GND")
	)
	(via
		(at 121.259092 -62.721744)
		(size 0.7112)
		(drill 0.4064)
		(layers "F.Cu" "B.Cu")
		(net "GND")
	)
	(via
		(at 69.93382 -106.162856)
		(size 0.7112)
		(drill 0.4064)
		(layers "F.Cu" "B.Cu")
		(net "GND")
	)
	(via
		(at 120.113298 -50.030888)
		(size 0.7112)
		(drill 0.4064)
		(layers "F.Cu" "B.Cu")
		(net "GND")
	)
	(via
		(at 142.367 -68.072)
		(size 0.7112)
		(drill 0.4064)
		(layers "F.Cu" "B.Cu")
		(net "GND")
	)
	(via
		(at 69.93382 -96.002856)
		(size 0.7112)
		(drill 0.4064)
		(layers "F.Cu" "B.Cu")
		(net "GND")
	)
	(segment
		(start 144.960086 -70.339966)
		(end 144.960086 -71.419974)
		(width 0.508)
		(layer "B.Cu")
		(net "GND")
	)
	(segment
		(start 148.960078 -65.259966)
		(end 150.040086 -65.259966)
		(width 0.508)
		(layer "B.Cu")
		(net "GND")
	)
	(segment
		(start 152.580086 -59.539886)
		(end 153.660094 -59.539886)
		(width 0.508)
		(layer "B.Cu")
		(net "GND")
	)
	(segment
		(start 150.040086 -62.079886)
		(end 151.120094 -62.079886)
		(width 0.508)
		(layer "B.Cu")
		(net "GND")
	)
	(segment
		(start 146.420078 -70.339966)
		(end 147.500086 -70.339966)
		(width 0.508)
		(layer "B.Cu")
		(net "GND")
	)
	(segment
		(start 150.040086 -70.339966)
		(end 151.120094 -70.339966)
		(width 0.508)
		(layer "B.Cu")
		(net "GND")
	)
	(segment
		(start 152.580086 -70.339966)
		(end 152.580086 -71.419974)
		(width 0.508)
		(layer "B.Cu")
		(net "GND")
	)
	(segment
		(start 152.580086 -67.799966)
		(end 153.660094 -67.799966)
		(width 0.508)
		(layer "B.Cu")
		(net "GND")
	)
	(segment
		(start 152.580086 -69.259958)
		(end 152.580086 -70.339966)
		(width 0.508)
		(layer "B.Cu")
		(net "GND")
	)
	(segment
		(start 144.960086 -66.719958)
		(end 144.960086 -67.799966)
		(width 0.508)
		(layer "B.Cu")
		(net "GND")
	)
	(segment
		(start 150.040086 -67.799966)
		(end 150.040086 -68.879974)
		(width 0.508)
		(layer "B.Cu")
		(net "GND")
	)
	(segment
		(start 152.580086 -67.799966)
		(end 152.580086 -68.879974)
		(width 0.508)
		(layer "B.Cu")
		(net "GND")
	)
	(segment
		(start 151.500078 -67.799966)
		(end 152.580086 -67.799966)
		(width 0.508)
		(layer "B.Cu")
		(net "GND")
	)
	(segment
		(start 146.420078 -72.879966)
		(end 147.500086 -72.879966)
		(width 0.508)
		(layer "B.Cu")
		(net "GND")
	)
	(segment
		(start 143.880078 -67.799966)
		(end 144.960086 -67.799966)
		(width 0.508)
		(layer "B.Cu")
		(net "GND")
	)
	(segment
		(start 150.040086 -71.799958)
		(end 150.040086 -72.879966)
		(width 0.508)
		(layer "B.Cu")
		(net "GND")
	)
	(segment
		(start 150.040086 -66.719958)
		(end 150.040086 -67.799966)
		(width 0.508)
		(layer "B.Cu")
		(net "GND")
	)
	(segment
		(start 146.420078 -65.259966)
		(end 147.500086 -65.259966)
		(width 0.508)
		(layer "B.Cu")
		(net "GND")
	)
	(segment
		(start 143.880078 -70.339966)
		(end 144.960086 -70.339966)
		(width 0.508)
		(layer "B.Cu")
		(net "GND")
	)
	(segment
		(start 152.580086 -72.879966)
		(end 152.580086 -73.959974)
		(width 0.508)
		(layer "B.Cu")
		(net "GND")
	)
	(segment
		(start -1.676908 -90.729308)
		(end -6.61797 -90.729308)
		(width 0.762)
		(layer "B.Cu")
		(net "GND")
	)
	(segment
		(start 152.580086 -70.339966)
		(end 153.660094 -70.339966)
		(width 0.508)
		(layer "B.Cu")
		(net "GND")
	)
	(segment
		(start 148.960078 -70.339966)
		(end 150.040086 -70.339966)
		(width 0.508)
		(layer "B.Cu")
		(net "GND")
	)
	(segment
		(start 144.960086 -67.799966)
		(end 144.960086 -68.879974)
		(width 0.508)
		(layer "B.Cu")
		(net "GND")
	)
	(segment
		(start 144.960086 -70.339966)
		(end 146.040094 -70.339966)
		(width 0.508)
		(layer "B.Cu")
		(net "GND")
	)
	(segment
		(start 147.500086 -65.259966)
		(end 147.500086 -66.339974)
		(width 0.508)
		(layer "B.Cu")
		(net "GND")
	)
	(segment
		(start 147.500086 -69.259958)
		(end 147.500086 -70.339966)
		(width 0.508)
		(layer "B.Cu")
		(net "GND")
	)
	(segment
		(start 148.960078 -67.799966)
		(end 150.040086 -67.799966)
		(width 0.508)
		(layer "B.Cu")
		(net "GND")
	)
	(segment
		(start 147.500086 -70.339966)
		(end 147.500086 -71.419974)
		(width 0.508)
		(layer "B.Cu")
		(net "GND")
	)
	(segment
		(start 144.960086 -72.879966)
		(end 146.040094 -72.879966)
		(width 0.508)
		(layer "B.Cu")
		(net "GND")
	)
	(segment
		(start 148.960078 -56.999886)
		(end 150.040086 -56.999886)
		(width 0.508)
		(layer "B.Cu")
		(net "GND")
	)
	(segment
		(start 152.580086 -72.879966)
		(end 153.660094 -72.879966)
		(width 0.508)
		(layer "B.Cu")
		(net "GND")
	)
	(segment
		(start 147.500086 -67.799966)
		(end 147.500086 -68.879974)
		(width 0.508)
		(layer "B.Cu")
		(net "GND")
	)
	(segment
		(start 152.580086 -58.459878)
		(end 152.580086 -59.539886)
		(width 0.508)
		(layer "B.Cu")
		(net "GND")
	)
	(segment
		(start 146.420078 -67.799966)
		(end 147.500086 -67.799966)
		(width 0.508)
		(layer "B.Cu")
		(net "GND")
	)
	(segment
		(start 143.880078 -65.259966)
		(end 144.960086 -65.259966)
		(width 0.508)
		(layer "B.Cu")
		(net "GND")
	)
	(segment
		(start 150.040086 -70.339966)
		(end 150.040086 -71.419974)
		(width 0.508)
		(layer "B.Cu")
		(net "GND")
	)
	(segment
		(start 150.040086 -69.259958)
		(end 150.040086 -70.339966)
		(width 0.508)
		(layer "B.Cu")
		(net "GND")
	)
	(segment
		(start 150.040086 -67.799966)
		(end 151.120094 -67.799966)
		(width 0.508)
		(layer "B.Cu")
		(net "GND")
	)
	(segment
		(start 147.500086 -72.879966)
		(end 148.580094 -72.879966)
		(width 0.508)
		(layer "B.Cu")
		(net "GND")
	)
	(segment
		(start 150.040086 -60.999878)
		(end 150.040086 -62.079886)
		(width 0.508)
		(layer "B.Cu")
		(net "GND")
	)
	(segment
		(start 150.040086 -62.079886)
		(end 150.040086 -63.159894)
		(width 0.508)
		(layer "B.Cu")
		(net "GND")
	)
	(segment
		(start 148.960078 -72.879966)
		(end 150.040086 -72.879966)
		(width 0.508)
		(layer "B.Cu")
		(net "GND")
	)
	(segment
		(start 147.500086 -71.799958)
		(end 147.500086 -72.879966)
		(width 0.508)
		(layer "B.Cu")
		(net "GND")
	)
	(segment
		(start 147.500086 -65.259966)
		(end 148.580094 -65.259966)
		(width 0.508)
		(layer "B.Cu")
		(net "GND")
	)
	(segment
		(start 152.580086 -65.259966)
		(end 153.660094 -65.259966)
		(width 0.508)
		(layer "B.Cu")
		(net "GND")
	)
	(segment
		(start 150.040086 -65.259966)
		(end 151.120094 -65.259966)
		(width 0.508)
		(layer "B.Cu")
		(net "GND")
	)
	(segment
		(start 144.960086 -71.799958)
		(end 144.960086 -72.879966)
		(width 0.508)
		(layer "B.Cu")
		(net "GND")
	)
	(segment
		(start 144.960086 -65.259966)
		(end 144.960086 -66.339974)
		(width 0.508)
		(layer "B.Cu")
		(net "GND")
	)
	(segment
		(start 152.580086 -66.719958)
		(end 152.580086 -67.799966)
		(width 0.508)
		(layer "B.Cu")
		(net "GND")
	)
	(segment
		(start 151.500078 -65.259966)
		(end 152.580086 -65.259966)
		(width 0.508)
		(layer "B.Cu")
		(net "GND")
	)
	(segment
		(start 150.040086 -72.879966)
		(end 150.040086 -73.959974)
		(width 0.508)
		(layer "B.Cu")
		(net "GND")
	)
	(segment
		(start 147.500086 -72.879966)
		(end 147.500086 -73.959974)
		(width 0.508)
		(layer "B.Cu")
		(net "GND")
	)
	(segment
		(start 152.580086 -54.459886)
		(end 152.580086 -55.539894)
		(width 0.508)
		(layer "B.Cu")
		(net "GND")
	)
	(segment
		(start 152.580086 -54.459886)
		(end 153.660094 -54.459886)
		(width 0.508)
		(layer "B.Cu")
		(net "GND")
	)
	(segment
		(start 151.500078 -70.339966)
		(end 152.580086 -70.339966)
		(width 0.508)
		(layer "B.Cu")
		(net "GND")
	)
	(segment
		(start 152.580086 -65.259966)
		(end 152.580086 -66.339974)
		(width 0.508)
		(layer "B.Cu")
		(net "GND")
	)
	(segment
		(start -6.61797 -85.649308)
		(end -1.803908 -85.649308)
		(width 0.762)
		(layer "B.Cu")
		(net "GND")
	)
	(segment
		(start 147.500086 -64.179958)
		(end 147.500086 -65.259966)
		(width 0.508)
		(layer "B.Cu")
		(net "GND")
	)
	(segment
		(start 150.040086 -65.259966)
		(end 150.040086 -66.339974)
		(width 0.508)
		(layer "B.Cu")
		(net "GND")
	)
	(segment
		(start 147.500086 -70.339966)
		(end 148.580094 -70.339966)
		(width 0.508)
		(layer "B.Cu")
		(net "GND")
	)
	(segment
		(start 144.960086 -65.259966)
		(end 146.040094 -65.259966)
		(width 0.508)
		(layer "B.Cu")
		(net "GND")
	)
	(segment
		(start 151.500078 -54.459886)
		(end 152.580086 -54.459886)
		(width 0.508)
		(layer "B.Cu")
		(net "GND")
	)
	(segment
		(start 150.040086 -64.179958)
		(end 150.040086 -65.259966)
		(width 0.508)
		(layer "B.Cu")
		(net "GND")
	)
	(segment
		(start 144.960086 -72.879966)
		(end 144.960086 -73.959974)
		(width 0.508)
		(layer "B.Cu")
		(net "GND")
	)
	(segment
		(start 144.960086 -69.259958)
		(end 144.960086 -70.339966)
		(width 0.508)
		(layer "B.Cu")
		(net "GND")
	)
	(segment
		(start 144.960086 -67.799966)
		(end 146.040094 -67.799966)
		(width 0.508)
		(layer "B.Cu")
		(net "GND")
	)
	(segment
		(start -6.61797 -76.759308)
		(end -0.748792 -76.759308)
		(width 0.762)
		(layer "B.Cu")
		(net "GND")
	)
	(segment
		(start 150.040086 -56.999886)
		(end 150.040086 -58.079894)
		(width 0.508)
		(layer "B.Cu")
		(net "GND")
	)
	(segment
		(start 150.040086 -55.919878)
		(end 150.040086 -56.999886)
		(width 0.508)
		(layer "B.Cu")
		(net "GND")
	)
	(segment
		(start 148.960078 -62.079886)
		(end 150.040086 -62.079886)
		(width 0.508)
		(layer "B.Cu")
		(net "GND")
	)
	(segment
		(start 152.580086 -64.179958)
		(end 152.580086 -65.259966)
		(width 0.508)
		(layer "B.Cu")
		(net "GND")
	)
	(segment
		(start -6.61797 -88.189308)
		(end -1.676908 -88.189308)
		(width 0.762)
		(layer "B.Cu")
		(net "GND")
	)
	(segment
		(start 151.500078 -72.879966)
		(end 152.580086 -72.879966)
		(width 0.508)
		(layer "B.Cu")
		(net "GND")
	)
	(segment
		(start 152.580086 -71.799958)
		(end 152.580086 -72.879966)
		(width 0.508)
		(layer "B.Cu")
		(net "GND")
	)
	(segment
		(start 152.580086 -59.539886)
		(end 152.580086 -60.619894)
		(width 0.508)
		(layer "B.Cu")
		(net "GND")
	)
	(segment
		(start 150.040086 -72.879966)
		(end 151.120094 -72.879966)
		(width 0.508)
		(layer "B.Cu")
		(net "GND")
	)
	(segment
		(start 150.040086 -56.999886)
		(end 151.120094 -56.999886)
		(width 0.508)
		(layer "B.Cu")
		(net "GND")
	)
	(segment
		(start 144.960086 -64.179958)
		(end 144.960086 -65.259966)
		(width 0.508)
		(layer "B.Cu")
		(net "GND")
	)
	(segment
		(start 147.500086 -67.799966)
		(end 148.580094 -67.799966)
		(width 0.508)
		(layer "B.Cu")
		(net "GND")
	)
	(segment
		(start 143.880078 -72.879966)
		(end 144.960086 -72.879966)
		(width 0.508)
		(layer "B.Cu")
		(net "GND")
	)
	(segment
		(start 147.500086 -66.719958)
		(end 147.500086 -67.799966)
		(width 0.508)
		(layer "B.Cu")
		(net "GND")
	)
	(segment
		(start 151.500078 -59.539886)
		(end 152.580086 -59.539886)
		(width 0.508)
		(layer "B.Cu")
		(net "GND")
	)
	(segment
		(start 119.932704 -83.041744)
		(end 35.26282 -83.041744)
		(width 0.1397)
		(layer "F.Cu")
		(net "I2C_C_BUF_SDA")
	)
	(segment
		(start 20.574 -94.687644)
		(end 17.98066 -94.687644)
		(width 0.1397)
		(layer "F.Cu")
		(net "I2C_C_BUF_SDA")
	)
	(segment
		(start 35.26282 -83.041744)
		(end 23.61692 -94.687644)
		(width 0.1397)
		(layer "F.Cu")
		(net "I2C_C_BUF_SDA")
	)
	(segment
		(start 135.077962 -67.896486)
		(end 119.932704 -83.041744)
		(width 0.1397)
		(layer "F.Cu")
		(net "I2C_C_BUF_SDA")
	)
	(segment
		(start 135.707882 -68.318634)
		(end 135.285734 -67.896486)
		(width 0.1397)
		(layer "F.Cu")
		(net "I2C_C_BUF_SDA")
	)
	(segment
		(start 135.285734 -67.896486)
		(end 135.077962 -67.896486)
		(width 0.1397)
		(layer "F.Cu")
		(net "I2C_C_BUF_SDA")
	)
	(segment
		(start 17.677638 -94.990666)
		(end 17.677638 -96.071182)
		(width 0.1397)
		(layer "F.Cu")
		(net "I2C_C_BUF_SDA")
	)
	(segment
		(start 17.677638 -96.071182)
		(end 17.6784 -96.071944)
		(width 0.1397)
		(layer "F.Cu")
		(net "I2C_C_BUF_SDA")
	)
	(segment
		(start 17.98066 -94.687644)
		(end 17.677638 -94.990666)
		(width 0.1397)
		(layer "F.Cu")
		(net "I2C_C_BUF_SDA")
	)
	(segment
		(start 23.61692 -94.687644)
		(end 20.574 -94.687644)
		(width 0.1397)
		(layer "F.Cu")
		(net "I2C_C_BUF_SDA")
	)
	(via
		(at 20.574 -94.687644)
		(size 0.7112)
		(drill 0.3556)
		(layers "F.Cu" "B.Cu")
		(net "I2C_C_BUF_SDA")
	)
	(segment
		(start -3.20294 -76.759308)
		(end -2.154174 -76.759308)
		(width 1.016)
		(layer "F.Cu")
		(net "P5VA")
	)
	(segment
		(start -6.99897 -76.759308)
		(end -3.20294 -76.759308)
		(width 0.762)
		(layer "F.Cu")
		(net "P5VA")
	)
	(segment
		(start 156.920692 -103.869744)
		(end 156.920692 -104.902)
		(width 0.762)
		(layer "F.Cu")
		(net "P5VA")
	)
	(segment
		(start 0.592836 -79.506318)
		(end 0.592836 -80.938116)
		(width 1.016)
		(layer "F.Cu")
		(net "P5VA")
	)
	(segment
		(start -2.154174 -76.759308)
		(end 0.592836 -79.506318)
		(width 1.016)
		(layer "F.Cu")
		(net "P5VA")
	)
	(via
		(at 5.308092 -82.660744)
		(size 0.7112)
		(drill 0.3556)
		(layers "F.Cu" "B.Cu")
		(net "P5VA")
	)
	(via
		(at 0.592836 -80.938116)
		(size 0.7112)
		(drill 0.4064)
		(layers "F.Cu" "B.Cu")
		(net "P5VA")
	)
	(via
		(at 156.920692 -104.902)
		(size 0.7112)
		(drill 0.4064)
		(layers "F.Cu" "B.Cu")
		(net "P5VA")
	)
	(via
		(at 136.245092 -106.409744)
		(size 0.7112)
		(drill 0.3556)
		(layers "F.Cu" "B.Cu")
		(net "P5VA")
	)
	(segment
		(start 2.315464 -82.660744)
		(end 0.592836 -80.938116)
		(width 1.016)
		(layer "B.Cu")
		(net "P5VA")
	)
	(segment
		(start 8.128 -97.028)
		(end 10.515092 -94.640908)
		(width 1.016)
		(layer "B.Cu")
		(net "P5VA")
	)
	(segment
		(start 7.975092 -82.660744)
		(end 5.308092 -82.660744)
		(width 1.016)
		(layer "B.Cu")
		(net "P5VA")
	)
	(segment
		(start 13.073888 -102.726236)
		(end 9.965944 -99.618292)
		(width 1.016)
		(layer "B.Cu")
		(net "P5VA")
	)
	(segment
		(start 10.515092 -85.200744)
		(end 7.975092 -82.660744)
		(width 1.016)
		(layer "B.Cu")
		(net "P5VA")
	)
	(segment
		(start 5.308092 -82.660744)
		(end 2.315464 -82.660744)
		(width 1.016)
		(layer "B.Cu")
		(net "P5VA")
	)
	(segment
		(start 10.515092 -94.640908)
		(end 10.515092 -85.200744)
		(width 1.016)
		(layer "B.Cu")
		(net "P5VA")
	)
	(segment
		(start 136.245092 -106.409744)
		(end 132.816092 -106.409744)
		(width 1.016)
		(layer "B.Cu")
		(net "P5VA")
	)
	(segment
		(start 13.074904 -102.726744)
		(end 13.073888 -102.726236)
		(width 1.016)
		(layer "B.Cu")
		(net "P5VA")
	)
	(segment
		(start 8.128 -98.685604)
		(end 8.128 -97.028)
		(width 1.016)
		(layer "B.Cu")
		(net "P5VA")
	)
	(segment
		(start 156.920692 -104.902)
		(end 156.920692 -105.413048)
		(width 1.016)
		(layer "B.Cu")
		(net "P5VA")
	)
	(segment
		(start 156.920692 -105.413048)
		(end 155.923996 -106.409744)
		(width 1.016)
		(layer "B.Cu")
		(net "P5VA")
	)
	(segment
		(start 9.965944 -99.618292)
		(end 9.061704 -99.618292)
		(width 1.016)
		(layer "B.Cu")
		(net "P5VA")
	)
	(segment
		(start 9.061704 -99.618292)
		(end 9.011412 -99.568)
		(width 1.016)
		(layer "B.Cu")
		(net "P5VA")
	)
	(segment
		(start 129.133092 -102.726744)
		(end 13.074904 -102.726744)
		(width 1.016)
		(layer "B.Cu")
		(net "P5VA")
	)
	(segment
		(start 155.923996 -106.409744)
		(end 136.245092 -106.409744)
		(width 1.016)
		(layer "B.Cu")
		(net "P5VA")
	)
	(segment
		(start 9.011412 -99.568)
		(end 9.010396 -99.568)
		(width 1.016)
		(layer "B.Cu")
		(net "P5VA")
	)
	(segment
		(start 132.816092 -106.409744)
		(end 129.133092 -102.726744)
		(width 1.016)
		(layer "B.Cu")
		(net "P5VA")
	)
	(segment
		(start 9.010396 -99.568)
		(end 8.128 -98.685604)
		(width 1.016)
		(layer "B.Cu")
		(net "P5VA")
	)
	(segment
		(start 136.737344 -83.972908)
		(end 137.346944 -83.363308)
		(width 0.1397)
		(layer "F.Cu")
		(net "TRAY_MOSFET_G")
	)
	(segment
		(start 132.588 -78.444852)
		(end 134.640574 -76.392278)
		(width 0.1397)
		(layer "F.Cu")
		(net "TRAY_MOSFET_G")
	)
	(segment
		(start 135.530844 -83.972908)
		(end 136.737344 -83.972908)
		(width 0.1397)
		(layer "F.Cu")
		(net "TRAY_MOSFET_G")
	)
	(segment
		(start 137.346944 -83.363308)
		(end 137.346944 -78.715108)
		(width 0.1397)
		(layer "F.Cu")
		(net "TRAY_MOSFET_G")
	)
	(segment
		(start 132.7785 -81.788)
		(end 132.588 -81.5975)
		(width 0.1397)
		(layer "F.Cu")
		(net "TRAY_MOSFET_G")
	)
	(segment
		(start 135.353044 -76.392278)
		(end 137.346944 -78.386178)
		(width 0.1397)
		(layer "F.Cu")
		(net "TRAY_MOSFET_G")
	)
	(segment
		(start 134.640574 -76.392278)
		(end 135.353044 -76.392278)
		(width 0.1397)
		(layer "F.Cu")
		(net "TRAY_MOSFET_G")
	)
	(segment
		(start 137.346944 -78.386178)
		(end 137.346944 -78.715108)
		(width 0.1397)
		(layer "F.Cu")
		(net "TRAY_MOSFET_G")
	)
	(segment
		(start 132.588 -81.5975)
		(end 132.588 -78.444852)
		(width 0.1397)
		(layer "F.Cu")
		(net "TRAY_MOSFET_G")
	)
	(via
		(at 137.346944 -78.715108)
		(size 0.7112)
		(drill 0.3556)
		(layers "F.Cu" "B.Cu")
		(net "TRAY_MOSFET_G")
	)
	(segment
		(start 23.72233 -93.845634)
		(end 18.999962 -93.845634)
		(width 0.1397)
		(layer "F.Cu")
		(net "I2C_C_BUF_SCL")
	)
	(segment
		(start 18.999962 -93.845634)
		(end 17.665446 -93.845634)
		(width 0.1397)
		(layer "F.Cu")
		(net "I2C_C_BUF_SCL")
	)
	(segment
		(start 119.716804 -82.521044)
		(end 35.04692 -82.521044)
		(width 0.1397)
		(layer "F.Cu")
		(net "I2C_C_BUF_SCL")
	)
	(segment
		(start 17.665192 -93.84538)
		(end 17.665192 -92.75318)
		(width 0.1397)
		(layer "F.Cu")
		(net "I2C_C_BUF_SCL")
	)
	(segment
		(start 35.04692 -82.521044)
		(end 23.72233 -93.845634)
		(width 0.1397)
		(layer "F.Cu")
		(net "I2C_C_BUF_SCL")
	)
	(segment
		(start 135.38073 -67.375786)
		(end 134.862062 -67.375786)
		(width 0.1397)
		(layer "F.Cu")
		(net "I2C_C_BUF_SCL")
	)
	(segment
		(start 134.862062 -67.375786)
		(end 119.716804 -82.521044)
		(width 0.1397)
		(layer "F.Cu")
		(net "I2C_C_BUF_SCL")
	)
	(segment
		(start 135.707882 -67.048634)
		(end 135.38073 -67.375786)
		(width 0.1397)
		(layer "F.Cu")
		(net "I2C_C_BUF_SCL")
	)
	(segment
		(start 17.665446 -93.845634)
		(end 17.665192 -93.84538)
		(width 0.1397)
		(layer "F.Cu")
		(net "I2C_C_BUF_SCL")
	)
	(segment
		(start 17.665192 -92.75318)
		(end 17.663414 -92.751402)
		(width 0.1397)
		(layer "F.Cu")
		(net "I2C_C_BUF_SCL")
	)
	(via
		(at 18.999962 -93.845634)
		(size 0.7112)
		(drill 0.3556)
		(layers "F.Cu" "B.Cu")
		(net "I2C_C_BUF_SCL")
	)
	(segment
		(start 152.415494 -19.4945)
		(end 152.910032 -18.999962)
		(width 0.1397)
		(layer "F.Cu")
		(net "TPS2490_EN2")
	)
	(segment
		(start 148.082 -19.4945)
		(end 152.415494 -19.4945)
		(width 0.1397)
		(layer "F.Cu")
		(net "TPS2490_EN2")
	)
	(via
		(at 155.637738 -23.627842)
		(size 0.7112)
		(drill 0.3556)
		(layers "F.Cu" "B.Cu")
		(net "TPS2490_EN2")
	)
	(segment
		(start 155.637738 -23.427436)
		(end 155.637738 -23.627842)
		(width 0.1397)
		(layer "B.Cu")
		(net "TPS2490_EN2")
	)
	(segment
		(start 152.910032 -20.69973)
		(end 155.637738 -23.427436)
		(width 0.1397)
		(layer "B.Cu")
		(net "TPS2490_EN2")
	)
	(segment
		(start 155.6385 -23.628604)
		(end 155.637738 -23.627842)
		(width 0.1397)
		(layer "B.Cu")
		(net "TPS2490_EN2")
	)
	(segment
		(start 155.6385 -52.1335)
		(end 155.6385 -23.628604)
		(width 0.1397)
		(layer "B.Cu")
		(net "TPS2490_EN2")
	)
	(segment
		(start 147.500086 -54.459886)
		(end 148.492972 -53.467)
		(width 0.1397)
		(layer "B.Cu")
		(net "TPS2490_EN2")
	)
	(segment
		(start 152.910032 -18.999962)
		(end 152.910032 -20.69973)
		(width 0.1397)
		(layer "B.Cu")
		(net "TPS2490_EN2")
	)
	(segment
		(start 154.305 -53.467)
		(end 155.6385 -52.1335)
		(width 0.1397)
		(layer "B.Cu")
		(net "TPS2490_EN2")
	)
	(segment
		(start 148.492972 -53.467)
		(end 154.305 -53.467)
		(width 0.1397)
		(layer "B.Cu")
		(net "TPS2490_EN2")
	)
	(segment
		(start 148.2725 -20.193)
		(end 150.60295 -20.193)
		(width 0.1397)
		(layer "F.Cu")
		(net "TPS2490_EN1")
	)
	(segment
		(start 148.082 -20.3835)
		(end 148.2725 -20.193)
		(width 0.1397)
		(layer "F.Cu")
		(net "TPS2490_EN1")
	)
	(segment
		(start 150.60295 -20.193)
		(end 151.409908 -20.999958)
		(width 0.1397)
		(layer "F.Cu")
		(net "TPS2490_EN1")
	)
	(via
		(at 154.94 -25.4)
		(size 0.7112)
		(drill 0.3556)
		(layers "F.Cu" "B.Cu")
		(net "TPS2490_EN1")
	)
	(segment
		(start 154.94 -23.749)
		(end 154.94 -25.4)
		(width 0.1397)
		(layer "B.Cu")
		(net "TPS2490_EN1")
	)
	(segment
		(start 155.194 -25.654)
		(end 154.94 -25.4)
		(width 0.1397)
		(layer "B.Cu")
		(net "TPS2490_EN1")
	)
	(segment
		(start 152.190958 -20.999958)
		(end 154.94 -23.749)
		(width 0.1397)
		(layer "B.Cu")
		(net "TPS2490_EN1")
	)
	(segment
		(start 153.924 -52.959)
		(end 155.194 -51.689)
		(width 0.1397)
		(layer "B.Cu")
		(net "TPS2490_EN1")
	)
	(segment
		(start 151.409908 -20.999958)
		(end 152.190958 -20.999958)
		(width 0.1397)
		(layer "B.Cu")
		(net "TPS2490_EN1")
	)
	(segment
		(start 148.5392 -52.959)
		(end 153.924 -52.959)
		(width 0.1397)
		(layer "B.Cu")
		(net "TPS2490_EN1")
	)
	(segment
		(start 155.194 -51.689)
		(end 155.194 -25.654)
		(width 0.1397)
		(layer "B.Cu")
		(net "TPS2490_EN1")
	)
	(segment
		(start 147.500086 -51.919886)
		(end 148.5392 -52.959)
		(width 0.1397)
		(layer "B.Cu")
		(net "TPS2490_EN1")
	)
	(segment
		(start 16.101314 -98.359468)
		(end 17.121632 -99.379786)
		(width 0.1397)
		(layer "F.Cu")
		(net "I2C_C_BUF_READY")
	)
	(segment
		(start 15.253208 -98.359468)
		(end 16.101314 -98.359468)
		(width 0.1397)
		(layer "F.Cu")
		(net "I2C_C_BUF_READY")
	)
	(segment
		(start 14.625828 -96.431608)
		(end 14.625828 -97.732088)
		(width 0.1397)
		(layer "F.Cu")
		(net "I2C_C_BUF_READY")
	)
	(segment
		(start 14.625828 -97.732088)
		(end 15.253208 -98.359468)
		(width 0.1397)
		(layer "F.Cu")
		(net "I2C_C_BUF_READY")
	)
	(segment
		(start 12.27455 -90.3986)
		(end 11.496802 -90.3986)
		(width 0.1397)
		(layer "F.Cu")
		(net "I2C_C_BUF_EN")
	)
	(segment
		(start 12.675108 -92.291408)
		(end 12.675108 -90.799158)
		(width 0.1397)
		(layer "F.Cu")
		(net "I2C_C_BUF_EN")
	)
	(segment
		(start 12.675108 -90.799158)
		(end 12.27455 -90.3986)
		(width 0.1397)
		(layer "F.Cu")
		(net "I2C_C_BUF_EN")
	)
	(segment
		(start 11.496802 -90.3986)
		(end 10.931652 -89.83345)
		(width 0.1397)
		(layer "F.Cu")
		(net "I2C_C_BUF_EN")
	)
	(via
		(at 10.931652 -89.83345)
		(size 0.7112)
		(drill 0.3556)
		(layers "F.Cu" "B.Cu")
		(net "I2C_C_BUF_EN")
	)
	(via
		(at 134.366 -89.789)
		(size 0.7112)
		(drill 0.3556)
		(layers "F.Cu" "B.Cu")
		(net "IR_SWITCH_E")
	)
	(segment
		(start 133.67258 -85.89899)
		(end 133.807962 -85.89899)
		(width 0.1397)
		(layer "F.Cu")
		(net "TRAY PRESENT_OUT_NET")
	)
	(segment
		(start 134.667244 -81.813908)
		(end 134.667244 -82.906108)
		(width 0.1397)
		(layer "F.Cu")
		(net "TRAY PRESENT_OUT_NET")
	)
	(segment
		(start 134.641844 -85.065108)
		(end 134.641844 -83.972908)
		(width 0.1397)
		(layer "F.Cu")
		(net "TRAY PRESENT_OUT_NET")
	)
	(segment
		(start 134.641844 -83.411822)
		(end 134.667244 -83.386422)
		(width 0.1397)
		(layer "F.Cu")
		(net "TRAY PRESENT_OUT_NET")
	)
	(segment
		(start 133.807962 -85.89899)
		(end 134.641844 -85.065108)
		(width 0.1397)
		(layer "F.Cu")
		(net "TRAY PRESENT_OUT_NET")
	)
	(segment
		(start 134.641844 -83.972908)
		(end 134.641844 -83.411822)
		(width 0.1397)
		(layer "F.Cu")
		(net "TRAY PRESENT_OUT_NET")
	)
	(segment
		(start 134.667244 -83.386422)
		(end 134.667244 -82.906108)
		(width 0.1397)
		(layer "F.Cu")
		(net "TRAY PRESENT_OUT_NET")
	)
	(via
		(at 133.67258 -85.89899)
		(size 0.7112)
		(drill 0.3556)
		(layers "F.Cu" "B.Cu")
		(net "TRAY PRESENT_OUT_NET")
	)
	(segment
		(start 153.858722 -74.487278)
		(end 136.650222 -74.487278)
		(width 0.1397)
		(layer "F.Cu")
		(net "SELF_TRAY_PRESENT")
	)
	(segment
		(start 147.066 -60.706)
		(end 148.209 -60.706)
		(width 0.1397)
		(layer "F.Cu")
		(net "SELF_TRAY_PRESENT")
	)
	(segment
		(start 23.557992 -82.787744)
		(end 23.558246 -82.787998)
		(width 0.1397)
		(layer "F.Cu")
		(net "SELF_TRAY_PRESENT")
	)
	(segment
		(start 146.177 -54.864)
		(end 146.177 -51.435)
		(width 0.1397)
		(layer "F.Cu")
		(net "SELF_TRAY_PRESENT")
	)
	(segment
		(start 155.2321 -51.816)
		(end 155.2321 -73.1139)
		(width 0.1397)
		(layer "F.Cu")
		(net "SELF_TRAY_PRESENT")
	)
	(segment
		(start 136.650222 -74.487278)
		(end 136.652 -74.4855)
		(width 0.1397)
		(layer "F.Cu")
		(net "SELF_TRAY_PRESENT")
	)
	(segment
		(start 148.336 -58.547)
		(end 147.32 -58.547)
		(width 0.1397)
		(layer "F.Cu")
		(net "SELF_TRAY_PRESENT")
	)
	(segment
		(start 146.685 -50.927)
		(end 154.3431 -50.927)
		(width 0.1397)
		(layer "F.Cu")
		(net "SELF_TRAY_PRESENT")
	)
	(segment
		(start 29.07411 -79.481426)
		(end 90.955622 -79.481426)
		(width 0.1397)
		(layer "F.Cu")
		(net "SELF_TRAY_PRESENT")
	)
	(segment
		(start 142.364714 -61.592714)
		(end 136.982454 -61.592714)
		(width 0.1397)
		(layer "F.Cu")
		(net "SELF_TRAY_PRESENT")
	)
	(segment
		(start 145.692114 -62.079886)
		(end 147.066 -60.706)
		(width 0.1397)
		(layer "F.Cu")
		(net "SELF_TRAY_PRESENT")
	)
	(segment
		(start 142.851886 -62.079886)
		(end 142.364714 -61.592714)
		(width 0.1397)
		(layer "F.Cu")
		(net "SELF_TRAY_PRESENT")
	)
	(segment
		(start 146.558 -57.785)
		(end 146.558 -55.245)
		(width 0.1397)
		(layer "F.Cu")
		(net "SELF_TRAY_PRESENT")
	)
	(segment
		(start 4.080256 -82.787744)
		(end 23.557992 -82.787744)
		(width 0.1397)
		(layer "F.Cu")
		(net "SELF_TRAY_PRESENT")
	)
	(segment
		(start 148.209 -60.706)
		(end 148.717 -60.198)
		(width 0.1397)
		(layer "F.Cu")
		(net "SELF_TRAY_PRESENT")
	)
	(segment
		(start 147.32 -58.547)
		(end 146.558 -57.785)
		(width 0.1397)
		(layer "F.Cu")
		(net "SELF_TRAY_PRESENT")
	)
	(segment
		(start 146.177 -51.435)
		(end 146.685 -50.927)
		(width 0.1397)
		(layer "F.Cu")
		(net "SELF_TRAY_PRESENT")
	)
	(segment
		(start 23.558246 -82.787998)
		(end 25.767792 -82.787998)
		(width 0.1397)
		(layer "F.Cu")
		(net "SELF_TRAY_PRESENT")
	)
	(segment
		(start 25.767792 -82.787998)
		(end 26.288746 -82.267044)
		(width 0.1397)
		(layer "F.Cu")
		(net "SELF_TRAY_PRESENT")
	)
	(segment
		(start 134.368794 -74.487278)
		(end 136.650222 -74.487278)
		(width 0.1397)
		(layer "F.Cu")
		(net "SELF_TRAY_PRESENT")
	)
	(segment
		(start 26.288746 -82.267044)
		(end 26.288746 -82.26679)
		(width 0.1397)
		(layer "F.Cu")
		(net "SELF_TRAY_PRESENT")
	)
	(segment
		(start 148.717 -58.928)
		(end 148.336 -58.547)
		(width 0.1397)
		(layer "F.Cu")
		(net "SELF_TRAY_PRESENT")
	)
	(segment
		(start 2.54 -84.328)
		(end 4.080256 -82.787744)
		(width 0.1397)
		(layer "F.Cu")
		(net "SELF_TRAY_PRESENT")
	)
	(segment
		(start 155.2321 -73.1139)
		(end 153.858722 -74.487278)
		(width 0.1397)
		(layer "F.Cu")
		(net "SELF_TRAY_PRESENT")
	)
	(segment
		(start 154.3431 -50.927)
		(end 155.2321 -51.816)
		(width 0.1397)
		(layer "F.Cu")
		(net "SELF_TRAY_PRESENT")
	)
	(segment
		(start 144.960086 -62.079886)
		(end 142.851886 -62.079886)
		(width 0.1397)
		(layer "F.Cu")
		(net "SELF_TRAY_PRESENT")
	)
	(segment
		(start 119.093742 -79.481426)
		(end 90.955622 -79.481426)
		(width 0.1397)
		(layer "F.Cu")
		(net "SELF_TRAY_PRESENT")
	)
	(segment
		(start 148.717 -60.198)
		(end 148.717 -58.928)
		(width 0.1397)
		(layer "F.Cu")
		(net "SELF_TRAY_PRESENT")
	)
	(segment
		(start 144.960086 -62.079886)
		(end 145.692114 -62.079886)
		(width 0.1397)
		(layer "F.Cu")
		(net "SELF_TRAY_PRESENT")
	)
	(segment
		(start 146.558 -55.245)
		(end 146.177 -54.864)
		(width 0.1397)
		(layer "F.Cu")
		(net "SELF_TRAY_PRESENT")
	)
	(segment
		(start 26.288746 -82.26679)
		(end 29.07411 -79.481426)
		(width 0.1397)
		(layer "F.Cu")
		(net "SELF_TRAY_PRESENT")
	)
	(segment
		(start 136.982454 -61.592714)
		(end 119.093742 -79.481426)
		(width 0.1397)
		(layer "F.Cu")
		(net "SELF_TRAY_PRESENT")
	)
	(via
		(at 2.54 -84.328)
		(size 0.7112)
		(drill 0.4064)
		(layers "F.Cu" "B.Cu")
		(net "SELF_TRAY_PRESENT")
	)
	(via
		(at 90.955622 -79.481426)
		(size 0.7112)
		(drill 0.3556)
		(layers "F.Cu" "B.Cu")
		(net "SELF_TRAY_PRESENT")
	)
	(segment
		(start -1.003808 -84.328)
		(end 2.54 -84.328)
		(width 0.1397)
		(layer "B.Cu")
		(net "SELF_TRAY_PRESENT")
	)
	(segment
		(start -3.973068 -83.109308)
		(end -3.147568 -83.934808)
		(width 0.1397)
		(layer "B.Cu")
		(net "SELF_TRAY_PRESENT")
	)
	(segment
		(start -1.397 -83.934808)
		(end -1.003808 -84.328)
		(width 0.1397)
		(layer "B.Cu")
		(net "SELF_TRAY_PRESENT")
	)
	(segment
		(start -6.61797 -83.109308)
		(end -3.973068 -83.109308)
		(width 0.1397)
		(layer "B.Cu")
		(net "SELF_TRAY_PRESENT")
	)
	(segment
		(start -3.147568 -83.934808)
		(end -1.397 -83.934808)
		(width 0.1397)
		(layer "B.Cu")
		(net "SELF_TRAY_PRESENT")
	)
	(segment
		(start 161.159952 -18.237962)
		(end 159.715962 -18.237962)
		(width 0.1397)
		(layer "F.Cu")
		(net "TPS2490_LED")
	)
	(segment
		(start 159.715962 -18.237962)
		(end 159.639 -18.161)
		(width 0.1397)
		(layer "F.Cu")
		(net "TPS2490_LED")
	)
	(segment
		(start 159.639 -18.161)
		(end 158.369 -18.161)
		(width 0.1397)
		(layer "F.Cu")
		(net "TPS2490_LED")
	)
	(segment
		(start 156.972 -18.161)
		(end 158.369 -18.161)
		(width 0.1397)
		(layer "F.Cu")
		(net "TPS2490_LED")
	)
	(via
		(at 158.369 -18.161)
		(size 0.7112)
		(drill 0.3556)
		(layers "F.Cu" "B.Cu")
		(net "TPS2490_LED")
	)
	(segment
		(start 8.927592 -85.835744)
		(end 8.431276 -85.835744)
		(width 0.1397)
		(layer "F.Cu")
		(net "PWM_EXP_B")
	)
	(segment
		(start 8.431276 -85.835744)
		(end 7.854442 -85.25891)
		(width 0.1397)
		(layer "F.Cu")
		(net "PWM_EXP_B")
	)
	(via
		(at 6.731 -83.930744)
		(size 0.7112)
		(drill 0.3556)
		(layers "F.Cu" "B.Cu")
		(net "PWM_EXP_B")
	)
	(via
		(at 7.854442 -85.25891)
		(size 0.7112)
		(drill 0.4064)
		(layers "F.Cu" "B.Cu")
		(net "PWM_EXP_B")
	)
	(segment
		(start 7.41426 -83.930744)
		(end 6.731 -83.930744)
		(width 0.1397)
		(layer "B.Cu")
		(net "PWM_EXP_B")
	)
	(segment
		(start -6.61797 -81.839308)
		(end -2.032 -81.839308)
		(width 0.1397)
		(layer "B.Cu")
		(net "PWM_EXP_B")
	)
	(segment
		(start -2.032 -81.839308)
		(end -0.178308 -83.693)
		(width 0.1397)
		(layer "B.Cu")
		(net "PWM_EXP_B")
	)
	(segment
		(start 4.826 -83.693)
		(end 5.063744 -83.930744)
		(width 0.1397)
		(layer "B.Cu")
		(net "PWM_EXP_B")
	)
	(segment
		(start 7.854442 -85.25891)
		(end 7.854442 -84.370926)
		(width 0.1397)
		(layer "B.Cu")
		(net "PWM_EXP_B")
	)
	(segment
		(start -0.178308 -83.693)
		(end 4.826 -83.693)
		(width 0.1397)
		(layer "B.Cu")
		(net "PWM_EXP_B")
	)
	(segment
		(start 5.063744 -83.930744)
		(end 6.731 -83.930744)
		(width 0.1397)
		(layer "B.Cu")
		(net "PWM_EXP_B")
	)
	(segment
		(start 7.854442 -84.370926)
		(end 7.41426 -83.930744)
		(width 0.1397)
		(layer "B.Cu")
		(net "PWM_EXP_B")
	)
	(segment
		(start 8.927592 -84.692744)
		(end 7.353808 -84.692744)
		(width 0.1397)
		(layer "F.Cu")
		(net "PWM_EXP_A")
	)
	(segment
		(start 7.353808 -84.692744)
		(end 6.787642 -85.25891)
		(width 0.1397)
		(layer "F.Cu")
		(net "PWM_EXP_A")
	)
	(via
		(at 3.556 -85.344)
		(size 0.7112)
		(drill 0.3556)
		(layers "F.Cu" "B.Cu")
		(net "PWM_EXP_A")
	)
	(via
		(at 6.787642 -85.25891)
		(size 0.7112)
		(drill 0.4064)
		(layers "F.Cu" "B.Cu")
		(net "PWM_EXP_A")
	)
	(segment
		(start -0.644652 -85.344)
		(end 3.556 -85.344)
		(width 0.1397)
		(layer "B.Cu")
		(net "PWM_EXP_A")
	)
	(segment
		(start -6.61797 -84.379308)
		(end -1.609344 -84.379308)
		(width 0.1397)
		(layer "B.Cu")
		(net "PWM_EXP_A")
	)
	(segment
		(start 6.702552 -85.344)
		(end 3.556 -85.344)
		(width 0.1397)
		(layer "B.Cu")
		(net "PWM_EXP_A")
	)
	(segment
		(start 6.787642 -85.25891)
		(end 6.702552 -85.344)
		(width 0.1397)
		(layer "B.Cu")
		(net "PWM_EXP_A")
	)
	(segment
		(start -1.609344 -84.379308)
		(end -0.644652 -85.344)
		(width 0.1397)
		(layer "B.Cu")
		(net "PWM_EXP_A")
	)
	(zone
		(net "DETECTOR_C")
		(layer "F.Cu")
		(hatch none 0.5)
		(connect_pads
			(clearance 0.5)
		)
		(min_thickness 0.25)
		(fill yes
			(thermal_gap 0.5)
			(thermal_bridge_width 0.5)
			(island_removal_mode 0)
		)
		(polygon
			(pts
				(xy 158.75 -102.362) (xy 159.131 -101.981) (xy 159.131 -97.409) (xy 158.75 -97.028) (xy 156.21 -97.028)
				(xy 156.083 -97.155) (xy 156.083 -99.949) (xy 155.067 -100.965) (xy 155.067 -102.235) (xy 155.067 -102.616)
				(xy 155.321 -102.87) (xy 158.242 -102.87)
			)
		)
	)
	(zone
		(layer "F.Cu")
		(hatch none 0.5)
		(connect_pads
			(clearance 0)
		)
		(min_thickness 0.25)
		(keepout
			(tracks allowed)
			(vias allowed)
			(pads allowed)
			(copperpour allowed)
			(footprints not_allowed)
		)
		(placement
			(enabled no)
			(sheetname "")
		)
		(fill
			(thermal_gap 0.5)
			(thermal_bridge_width 0.5)
			(island_removal_mode 0)
		)
		(polygon
			(pts
				(arc
					(start 7.659878 -10.999978)
					(mid 12.159996 -15.500096)
					(end 7.659878 -19.99996)
				)
				(xy 0 -19.99996)
				(arc
					(start 0 -27.170126)
					(mid -0.292893 -27.877231)
					(end -0.999998 -28.170124)
				)
				(xy -9.500108 -28.170124) (xy -9.500108 -74.179938)
				(arc
					(start -0.350012 -74.179938)
					(mid 0 -74.52995)
					(end -0.350012 -74.879962)
				)
				(xy -9.500108 -74.879962) (xy -9.500108 -92.95003)
				(arc
					(start -0.999998 -92.95003)
					(mid -0.292893 -93.242923)
					(end 0 -93.950028)
				)
				(xy 0 -101.000052)
				(arc
					(start 7.659878 -101.000052)
					(mid 12.159996 -105.50017)
					(end 7.659878 -110.000034)
				)
				(xy 0 -110.000034)
				(arc
					(start 0 -119.000016)
					(mid 0.292893 -119.707121)
					(end 0.999998 -120.000014)
				)
				(arc
					(start 161.660078 -120.000014)
					(mid 162.367183 -119.707121)
					(end 162.660076 -119.000016)
				)
				(xy 162.660076 -102.14991) (xy 144.159986 -102.14991) (xy 144.159986 -96.149922)
				(arc
					(start 138.660124 -96.149922)
					(mid 137.953019 -95.857029)
					(end 137.660126 -95.149924)
				)
				(arc
					(start 137.660126 -90.849958)
					(mid 137.953019 -90.142853)
					(end 138.660124 -89.84996)
				)
				(xy 144.159986 -89.84996) (xy 144.159986 -12.850114) (xy 162.660076 -12.850114)
				(arc
					(start 162.660076 -0.999998)
					(mid 162.367183 -0.292893)
					(end 161.660078 0)
				)
				(arc
					(start 0.999998 0)
					(mid 0.292893 -0.292893)
					(end 0 -0.999998)
				)
				(xy 0 -10.999978)
			)
		)
	)
	(zone
		(layer "F.Cu")
		(hatch none 0.5)
		(connect_pads
			(clearance 0)
		)
		(min_thickness 0.25)
		(keepout
			(tracks allowed)
			(vias allowed)
			(pads allowed)
			(copperpour allowed)
			(footprints not_allowed)
		)
		(placement
			(enabled no)
			(sheetname "")
		)
		(fill
			(thermal_gap 0.5)
			(thermal_bridge_width 0.5)
			(island_removal_mode 0)
		)
		(polygon
			(pts
				(xy 144.159986 -102.14991) (xy 162.660076 -102.14991)
				(arc
					(start 162.660076 -98.685096)
					(mid 162.541691 -98.213381)
					(end 162.214814 -97.853246)
				)
				(arc
					(start 159.911796 -96.31807)
					(mid 159.647 -96.192958)
					(end 159.357314 -96.149922)
				)
				(xy 144.159986 -96.149922)
			)
		)
	)
	(zone
		(net "P3V3")
		(layer "F.Cu")
		(hatch none 0.5)
		(connect_pads
			(clearance 0.5)
		)
		(min_thickness 0.25)
		(fill yes
			(thermal_gap 0.5)
			(thermal_bridge_width 0.5)
			(island_removal_mode 0)
		)
		(polygon
			(pts
				(xy 151.993092 -89.010744) (xy 152.755092 -89.010744) (xy 153.085292 -89.010744) (xy 153.263092 -89.010744)
				(xy 154.990292 -89.010744) (xy 155.345892 -88.655144) (xy 155.345892 -86.106) (xy 154.952446 -85.712554)
				(xy 154.774392 -85.5345) (xy 150.802848 -85.5345) (xy 150.485348 -85.852) (xy 150.485348 -87.503)
				(xy 150.485348 -88.636348) (xy 150.859744 -89.010744)
			)
		)
	)
	(zone
		(net "IR_SWITCH_E")
		(layer "F.Cu")
		(hatch none 0.5)
		(connect_pads
			(clearance 0.5)
		)
		(min_thickness 0.25)
		(fill yes
			(thermal_gap 0.5)
			(thermal_bridge_width 0.5)
			(island_removal_mode 0)
		)
		(polygon
			(pts
				(xy 154.837892 -99.450144) (xy 154.964892 -99.323144) (xy 154.964892 -96.948244) (xy 151.472392 -96.948244)
				(xy 151.027892 -97.392744) (xy 137.311892 -97.392744) (xy 136.219692 -96.300544) (xy 136.219692 -87.512144)
				(xy 136.219692 -84.963) (xy 135.98271 -84.726018) (xy 135.780018 -84.726018) (xy 135.382 -84.726018)
				(xy 135.255 -84.853018) (xy 135.255 -85.217) (xy 135.128 -85.344) (xy 135.128 -85.378036) (xy 134.060692 -86.445344)
				(xy 134.060692 -97.773744) (xy 135.737092 -99.450144)
			)
		)
	)
	(zone
		(net "P12V")
		(layer "F.Cu")
		(hatch none 0.5)
		(connect_pads
			(clearance 0.5)
		)
		(min_thickness 0.25)
		(fill yes
			(thermal_gap 0.5)
			(thermal_bridge_width 0.5)
			(island_removal_mode 0)
		)
		(polygon
			(pts
				(xy 123.291092 -46.973744) (xy 124.434092 -46.973744) (xy 140.826744 -46.973744) (xy 140.843 -46.99)
				(xy 141.224 -46.99) (xy 144.272 -50.038) (xy 153.797 -50.038) (xy 154.432 -49.403) (xy 154.432 -41.148)
				(xy 149.606 -36.322) (xy 149.606 -29.972) (xy 149.606 -28.321) (xy 150.368 -27.559) (xy 155.194 -27.559)
				(xy 157.988 -24.765) (xy 157.988 -24.13) (xy 157.988 -19.431) (xy 157.988 -19.304) (xy 157.861 -19.177)
				(xy 157.734 -19.177) (xy 156.337 -19.177) (xy 156.21 -19.304) (xy 156.21 -23.241) (xy 154.559 -24.892)
				(xy 147.828 -24.892) (xy 147.447 -24.892) (xy 138.921744 -16.366744) (xy 127.990092 -16.366744)
				(xy 14.351 -16.366744) (xy 9.635744 -21.082) (xy 1.397 -21.082) (xy 0.762 -21.717) (xy 0.762 -22.86)
				(xy 0.762 -28.151836) (xy -0.233934 -29.14777) (xy -7.8359 -29.14777) (xy -7.839964 -29.152088)
				(xy -8.366252 -29.152088) (xy -8.458708 -29.244544) (xy -8.458708 -38.413944) (xy -8.291068 -38.581584)
				(xy -3.198876 -38.581584) (xy -3.130804 -38.649656) (xy -3.130804 -39.252906) (xy -3.21183 -39.333932)
				(xy -8.388096 -39.333932) (xy -8.458708 -39.404544) (xy -8.458708 -48.624744) (xy -8.325612 -48.75784)
				(xy 103.89616 -48.75784) (xy 105.680256 -46.973744) (xy 117.735096 -46.973744)
			)
		)
	)
	(zone
		(layer "F.Cu")
		(hatch none 0.5)
		(connect_pads
			(clearance 0)
		)
		(min_thickness 0.25)
		(keepout
			(tracks allowed)
			(vias allowed)
			(pads allowed)
			(copperpour allowed)
			(footprints not_allowed)
		)
		(placement
			(enabled no)
			(sheetname "")
		)
		(fill
			(thermal_gap 0.5)
			(thermal_bridge_width 0.5)
			(island_removal_mode 0)
		)
		(polygon
			(pts
				(arc
					(start 7.659878 -10.999978)
					(mid 12.159996 -15.500096)
					(end 7.659878 -19.99996)
				)
				(xy 0 -19.99996) (xy 0 -10.999978)
			)
		)
	)
	(zone
		(layer "F.Cu")
		(hatch none 0.5)
		(connect_pads
			(clearance 0)
		)
		(min_thickness 0.25)
		(keepout
			(tracks allowed)
			(vias allowed)
			(pads allowed)
			(copperpour allowed)
			(footprints not_allowed)
		)
		(placement
			(enabled no)
			(sheetname "")
		)
		(fill
			(thermal_gap 0.5)
			(thermal_bridge_width 0.5)
			(island_removal_mode 0)
		)
		(polygon
			(pts
				(arc
					(start 126.659894 -1.500124)
					(mid 131.160012 -6.000242)
					(end 126.659894 -10.500106)
				)
				(arc
					(start 114.659918 -10.500106)
					(mid 110.160054 -6.000242)
					(end 114.659918 -1.500124)
				)
			)
		)
	)
	(zone
		(layer "F.Cu")
		(hatch none 0.5)
		(connect_pads
			(clearance 0)
		)
		(min_thickness 0.25)
		(keepout
			(tracks allowed)
			(vias allowed)
			(pads allowed)
			(copperpour allowed)
			(footprints not_allowed)
		)
		(placement
			(enabled no)
			(sheetname "")
		)
		(fill
			(thermal_gap 0.5)
			(thermal_bridge_width 0.5)
			(island_removal_mode 0)
		)
		(polygon
			(pts
				(arc
					(start 6.379972 -63.5)
					(mid 7.087077 -63.207107)
					(end 7.37997 -62.500002)
				)
				(arc
					(start 7.37997 -57.500012)
					(mid 7.087077 -56.792907)
					(end 6.379972 -56.500014)
				)
				(arc
					(start 5.379974 -56.500014)
					(mid 4.672869 -56.792907)
					(end 4.379976 -57.500012)
				)
				(arc
					(start 4.379976 -62.500002)
					(mid 4.672869 -63.207107)
					(end 5.379974 -63.5)
				)
			)
		)
	)
	(zone
		(net "GND")
		(layer "F.Cu")
		(hatch none 0.5)
		(connect_pads
			(clearance 0.5)
		)
		(min_thickness 0.25)
		(fill yes
			(thermal_gap 0.5)
			(thermal_bridge_width 0.5)
			(island_removal_mode 0)
		)
		(polygon
			(pts
				(xy 15.367 -91.567) (xy 15.367 -88.29675) (xy 14.937486 -87.867236) (xy 11.952986 -87.867236) (xy 10.313162 -89.50706)
				(xy 10.313162 -89.507314) (xy 10.233406 -89.58707) (xy 10.233406 -92.524834) (xy 10.07491 -92.68333)
				(xy 8.567166 -92.68333) (xy 8.26643 -92.382594) (xy 8.26643 -91.74988) (xy 7.594854 -91.078304)
				(xy 6.157722 -91.078304) (xy 4.392422 -89.313004) (xy 4.392422 -87.453978) (xy 5.235956 -86.610444)
				(xy 10.78103 -86.610444) (xy 11.920474 -85.471) (xy 15.748 -85.471) (xy 30.263846 -85.471) (xy 30.44825 -85.655404)
				(xy 30.44825 -86.01075) (xy 24.638 -91.821) (xy 17.907 -91.821) (xy 17.846548 -91.821) (xy 17.54505 -91.519502)
				(xy 17.54505 -91.052142) (xy 17.538954 -91.046046) (xy 17.233392 -90.740484) (xy 16.375126 -90.740484)
				(xy 16.10995 -91.00566) (xy 16.10995 -91.58605) (xy 16.002 -91.694) (xy 15.494 -91.694)
			)
		)
	)
	(zone
		(net "GND")
		(layer "F.Cu")
		(hatch none 0.5)
		(connect_pads
			(clearance 0.5)
		)
		(min_thickness 0.25)
		(fill yes
			(thermal_gap 0.5)
			(thermal_bridge_width 0.5)
			(island_removal_mode 0)
		)
		(polygon
			(pts
				(xy -3.932174 -77.644244) (xy -7.880604 -77.644244) (xy -7.887716 -77.644244) (xy -7.949184 -77.705712)
				(xy -7.949184 -77.761338) (xy -7.949184 -78.400402) (xy -7.924292 -78.425294) (xy -7.883906 -78.425294)
				(xy -7.883652 -78.42504) (xy -4.490466 -78.42504) (xy -4.470146 -78.44536) (xy -4.470146 -78.866492)
				(xy -4.496816 -78.893162) (xy -7.905496 -78.893162) (xy -7.949184 -78.93685) (xy -7.949184 -79.5909)
				(xy -7.874508 -79.665576) (xy -4.516882 -79.665576) (xy -4.516628 -79.665322) (xy -3.999738 -79.665322)
				(xy -3.023362 -79.665322) (xy -1.850644 -80.83804) (xy -0.44958 -80.83804) (xy -0.254508 -80.642968)
				(xy -0.254508 -80.483202) (xy -0.254508 -79.808578) (xy -0.445262 -79.617824) (xy -2.418842 -77.644244)
			)
		)
	)
	(zone
		(net "EMITTER_K")
		(layer "F.Cu")
		(hatch none 0.5)
		(connect_pads
			(clearance 0.5)
		)
		(min_thickness 0.25)
		(fill yes
			(thermal_gap 0.5)
			(thermal_bridge_width 0.5)
			(island_removal_mode 0)
		)
		(polygon
			(pts
				(xy 158.5722 -89.086436) (xy 158.647892 -89.010744) (xy 158.647892 -84.641944) (xy 158.647892 -84.260944)
				(xy 157.758892 -83.371944) (xy 157.377892 -83.371944) (xy 155.980892 -83.371944) (xy 139.259056 -83.371944)
				(xy 139.065 -83.566) (xy 139.065 -84.709) (xy 139.065 -84.963) (xy 139.192 -85.09) (xy 155.448 -85.09)
				(xy 155.575 -85.217) (xy 155.853892 -85.495892) (xy 155.853892 -89.010744) (xy 155.929584 -89.086436)
			)
		)
	)
	(zone
		(layer "F.Cu")
		(hatch none 0.5)
		(connect_pads
			(clearance 0)
		)
		(min_thickness 0.25)
		(keepout
			(tracks allowed)
			(vias allowed)
			(pads allowed)
			(copperpour allowed)
			(footprints not_allowed)
		)
		(placement
			(enabled no)
			(sheetname "")
		)
		(fill
			(thermal_gap 0.5)
			(thermal_bridge_width 0.5)
			(island_removal_mode 0)
		)
		(polygon
			(pts
				(arc
					(start 7.659878 -101.000052)
					(mid 12.159996 -105.50017)
					(end 7.659878 -110.000034)
				)
				(xy 0 -110.000034) (xy 0 -101.000052)
			)
		)
	)
	(zone
		(layer "F.Cu")
		(hatch none 0.5)
		(connect_pads
			(clearance 0)
		)
		(min_thickness 0.25)
		(keepout
			(tracks allowed)
			(vias allowed)
			(pads allowed)
			(copperpour allowed)
			(footprints not_allowed)
		)
		(placement
			(enabled no)
			(sheetname "")
		)
		(fill
			(thermal_gap 0.5)
			(thermal_bridge_width 0.5)
			(island_removal_mode 0)
		)
		(polygon
			(pts
				(arc
					(start 161.660078 -33.53689)
					(mid 162.367183 -33.243997)
					(end 162.660076 -32.536892)
				)
				(xy 162.660076 -12.850114) (xy 144.159986 -12.850114) (xy 144.159986 -89.84996)
				(arc
					(start 159.357314 -89.84996)
					(mid 159.646996 -89.807083)
					(end 159.911796 -89.682066)
				)
				(arc
					(start 162.214814 -88.14689)
					(mid 162.54181 -87.786674)
					(end 162.660076 -87.314786)
				)
				(arc
					(start 162.660076 -81.46288)
					(mid 162.367183 -80.755775)
					(end 161.660078 -80.462882)
				)
				(arc
					(start 158.660084 -80.462882)
					(mid 157.952979 -80.169989)
					(end 157.660086 -79.462884)
				)
				(arc
					(start 157.660086 -34.536888)
					(mid 157.952979 -33.829783)
					(end 158.660084 -33.53689)
				)
			)
		)
	)
	(zone
		(net "GND")
		(layer "F.Cu")
		(hatch none 0.5)
		(connect_pads
			(clearance 0.5)
		)
		(min_thickness 0.25)
		(fill yes
			(thermal_gap 0.5)
			(thermal_bridge_width 0.5)
			(island_removal_mode 0)
		)
		(polygon
			(pts
				(xy 1.112774 -0.813562) (xy 0.762 -1.164336) (xy 0.762 -19.558) (xy 1.397 -20.193) (xy 9.398 -20.193)
				(xy 13.716 -15.875) (xy 139.192 -15.875) (xy 147.574 -24.257) (xy 154.305 -24.257) (xy 155.702 -22.86)
				(xy 155.702 -18.542) (xy 156.083 -18.161) (xy 156.083 -17.526) (xy 156.21 -17.399) (xy 158.692342 -17.399)
				(xy 159.079692 -17.786096) (xy 160.424876 -17.786096) (xy 160.668716 -17.542256) (xy 161.656522 -17.542256)
				(xy 161.81832 -17.704054) (xy 161.81832 -18.886932) (xy 161.664396 -19.040856) (xy 160.63722 -19.040856)
				(xy 160.265364 -18.669) (xy 159.004 -18.669) (xy 158.496 -19.177) (xy 158.496 -24.892) (xy 155.321 -28.067)
				(xy 151.13 -28.067) (xy 150.749 -28.448) (xy 150.749 -35.941) (xy 155.702 -40.894) (xy 155.702 -67.945)
				(xy 153.797 -69.85) (xy 141.478 -69.85) (xy 141.097 -69.469) (xy 135.91921 -69.469) (xy 121.727214 -83.660996)
				(xy 35.634168 -83.660996) (xy 24.12492 -95.170244) (xy 20.988782 -95.170244) (xy 18.861786 -97.29724)
				(xy 18.861786 -99.502214) (xy 17.415256 -100.948744) (xy 12.674092 -100.948744) (xy 12.166092 -100.440744)
				(xy 12.166092 -99.551744) (xy 12.039092 -99.424744) (xy 11.150092 -99.424744) (xy 10.864596 -99.139248)
				(xy 8.817356 -99.139248) (xy 8.633714 -98.955606) (xy 8.633714 -97.868486) (xy 9.020556 -97.481644)
				(xy 9.989058 -97.481644) (xy 10.109962 -97.36074) (xy 10.109962 -96.10344) (xy 9.934194 -95.927672)
				(xy 8.664702 -95.927672) (xy 7.610602 -96.981772) (xy 6.642862 -96.981772) (xy 6.267704 -96.60636)
				(xy 6.267704 -95.243142) (xy 4.34467 -93.320108) (xy 4.34594 -93.318838) (xy 4.34594 -92.334842)
				(xy -0.145288 -87.843614) (xy -1.88722 -87.843614) (xy -2.565908 -88.522302) (xy -2.565908 -91.931744)
				(xy -2.438908 -92.058744) (xy -0.279908 -92.058744) (xy 0.863092 -93.201744) (xy 0.863092 -118.855744)
				(xy 1.244092 -119.236744) (xy 161.518092 -119.236744) (xy 161.864294 -118.890542) (xy 161.864294 -98.57486)
				(xy 160.832038 -97.882964) (xy 159.893 -97.882964) (xy 159.512 -98.263964) (xy 159.512 -102.743)
				(xy 158.4325 -103.8225) (xy 158.4325 -105.6005) (xy 157.861 -106.172) (xy 154.686 -106.172) (xy 154.152092 -105.638092)
				(xy 154.152092 -101.075744) (xy 153.517092 -100.440744) (xy 135.330692 -100.440744) (xy 133.044692 -98.154744)
				(xy 133.044692 -85.988144) (xy 131.605274 -84.548726) (xy 131.605274 -78.452726) (xy 133.604 -76.454)
				(xy 133.604 -74.041) (xy 134.112 -73.533) (xy 135.128 -73.533) (xy 136.779 -73.533) (xy 137.3505 -74.1045)
				(xy 137.3505 -75.7555) (xy 137.3505 -76.2635) (xy 138.811 -77.724) (xy 138.811 -82.042) (xy 139.319 -82.55)
				(xy 155.956 -82.55) (xy 155.972256 -82.533744) (xy 157.962092 -82.533744) (xy 159.359092 -83.930744)
				(xy 159.359092 -88.227662) (xy 159.554164 -88.422734) (xy 160.299146 -88.422734) (xy 161.891726 -87.357966)
				(xy 161.891726 -81.661) (xy 161.637726 -81.407) (xy 157.988 -81.407) (xy 156.845 -80.264) (xy 156.845 -76.327)
				(xy 156.845 -33.782) (xy 157.861 -32.766) (xy 161.417 -32.766) (xy 161.891726 -32.291274) (xy 161.891726 -28.448)
				(xy 161.891726 -1.03632) (xy 161.668968 -0.813562)
			)
		)
		(polygon
			(pts
				(xy 11.176 -100.457) (xy 10.795 -100.457) (xy 10.795 -100.838) (xy 11.176 -100.838)
			)
		)
		(polygon
			(pts
				(xy 10.16 -99.695) (xy 9.779 -99.695) (xy 9.779 -100.076) (xy 10.16 -100.076)
			)
		)
		(polygon
			(pts
				(xy 138.557 -70.231) (xy 138.176 -70.231) (xy 138.176 -70.612) (xy 138.557 -70.612)
			)
		)
		(polygon
			(pts
				(xy 137.287 -70.231) (xy 136.906 -70.231) (xy 136.906 -70.612) (xy 137.287 -70.612)
			)
		)
		(polygon
			(pts
				(xy 148.035518 -16.374364) (xy 147.240498 -16.374364) (xy 147.012914 -16.601948) (xy 147.012914 -17.397476)
				(xy 147.218908 -17.60347) (xy 148.021802 -17.60347) (xy 148.138134 -17.487138) (xy 150.493222 -17.487138)
				(xy 150.482046 -17.475962) (xy 150.482046 -17.394936) (xy 150.560532 -17.31645) (xy 150.560532 -16.674592)
				(xy 150.451566 -16.565626) (xy 148.22678 -16.565626)
			)
		)
	)
	(zone
		(net "GND")
		(layer "F.Cu")
		(hatch none 0.5)
		(connect_pads
			(clearance 0.5)
		)
		(min_thickness 0.25)
		(fill yes
			(thermal_gap 0.5)
			(thermal_bridge_width 0.5)
			(island_removal_mode 0)
		)
		(polygon
			(pts
				(xy 140.064744 -47.735744) (xy 123.926092 -47.735744) (xy 118.253256 -47.735744) (xy 106.061256 -47.735744)
				(xy 104.283256 -49.513744) (xy -8.357108 -49.513744) (xy -8.458708 -49.615344) (xy -8.458708 -58.759344)
				(xy -8.306308 -58.911744) (xy -3.184652 -58.911744) (xy -3.140964 -58.955432) (xy -3.140964 -59.601862)
				(xy -3.19405 -59.654948) (xy -8.287512 -59.654948) (xy -8.433308 -59.800744) (xy -8.433308 -68.919344)
				(xy -8.282686 -69.069966) (xy -3.20294 -69.069966) (xy -3.165602 -69.107304) (xy -3.165602 -69.775832)
				(xy -3.204464 -69.814694) (xy -8.312658 -69.814694) (xy -8.433308 -69.935344) (xy -8.433308 -73.249028)
				(xy -8.27659 -73.405746) (xy 0.206756 -73.405746) (xy 0.736092 -73.935082) (xy 5.651754 -78.850744)
				(xy 24.485092 -78.850744) (xy 27.787092 -75.548744) (xy 28.01239 -75.323446) (xy 115.553236 -75.323446)
				(xy 118.369334 -75.323446) (xy 135.141716 -58.551064) (xy 136.13384 -58.551064) (xy 138.176 -58.551064)
				(xy 138.176 -58.547) (xy 140.589 -58.547) (xy 142.5575 -56.5785) (xy 142.748 -56.388) (xy 142.748 -52.324)
				(xy 142.748 -49.784) (xy 140.699744 -47.735744)
			)
		)
	)
	(zone
		(layer "F.Cu")
		(hatch none 0.5)
		(connect_pads
			(clearance 0)
		)
		(min_thickness 0.25)
		(keepout
			(tracks allowed)
			(vias allowed)
			(pads allowed)
			(copperpour allowed)
			(footprints not_allowed)
		)
		(placement
			(enabled no)
			(sheetname "")
		)
		(fill
			(thermal_gap 0.5)
			(thermal_bridge_width 0.5)
			(island_removal_mode 0)
		)
		(polygon
			(pts
				(arc
					(start 149.660102 -109.499908)
					(mid 154.16022 -114.000026)
					(end 149.660102 -118.49989)
				)
				(arc
					(start 137.660126 -118.49989)
					(mid 133.160262 -114.000026)
					(end 137.660126 -109.499908)
				)
			)
		)
	)
	(zone
		(layers "F.Cu" "B.Cu" "In1.Cu" "In2.Cu")
		(hatch none 0.5)
		(connect_pads
			(clearance 0)
		)
		(min_thickness 0.25)
		(keepout
			(tracks not_allowed)
			(vias allowed)
			(pads allowed)
			(copperpour not_allowed)
			(footprints allowed)
		)
		(placement
			(enabled no)
			(sheetname "")
		)
		(fill
			(thermal_gap 0.5)
			(thermal_bridge_width 0.5)
			(island_removal_mode 0)
		)
		(polygon
			(pts
				(arc
					(start 8.14197 -57.500012)
					(mid 7.625893 -56.254091)
					(end 6.379972 -55.738014)
				)
				(arc
					(start 5.379974 -55.738014)
					(mid 4.134053 -56.254091)
					(end 3.617976 -57.500012)
				)
				(arc
					(start 3.617976 -62.500002)
					(mid 4.134053 -63.745923)
					(end 5.379974 -64.262)
				)
				(arc
					(start 6.379972 -64.262)
					(mid 7.625893 -63.745923)
					(end 8.14197 -62.500002)
				)
			)
		)
	)
	(zone
		(layers "F.Cu" "B.Cu" "In1.Cu" "In2.Cu")
		(name "Package Keepin")
		(hatch none 0.5)
		(connect_pads
			(clearance 0)
		)
		(min_thickness 0.25)
		(keepout
			(tracks allowed)
			(vias allowed)
			(pads allowed)
			(copperpour allowed)
			(footprints allowed)
		)
		(placement
			(enabled no)
			(sheetname "")
		)
		(fill
			(thermal_gap 0.5)
			(thermal_bridge_width 0.5)
			(island_removal_mode 0)
		)
		(polygon
			(pts
				(xy 3.9878 -3.9878)
				(arc
					(start 3.9878 -27.170126)
					(mid 2.526908 -30.697032)
					(end -0.999998 -32.157924)
				)
				(xy -7.012178 -32.157924) (xy -7.012178 -70.192138)
				(arc
					(start -0.350012 -70.192138)
					(mid 3.9878 -74.52995)
					(end -0.350012 -78.867762)
				)
				(xy -7.012178 -78.867762) (xy -7.012178 -88.96223)
				(arc
					(start -0.999998 -88.96223)
					(mid 2.526908 -90.423122)
					(end 3.9878 -93.950028)
				)
				(xy 3.9878 -116.012214) (xy 158.672276 -116.012214) (xy 158.672276 -100.28428) (xy 158.452312 -100.137722)
				(arc
					(start 138.660124 -100.137722)
					(mid 135.133218 -98.67683)
					(end 133.672326 -95.149924)
				)
				(arc
					(start 133.672326 -90.849958)
					(mid 135.133218 -87.323052)
					(end 138.660124 -85.86216)
				)
				(xy 158.452566 -85.86216) (xy 158.672276 -85.715856) (xy 158.672276 -84.450682)
				(arc
					(start 158.660084 -84.450682)
					(mid 155.133178 -82.98979)
					(end 153.672286 -79.462884)
				)
				(arc
					(start 153.672286 -34.536888)
					(mid 155.133178 -31.009982)
					(end 158.660084 -29.54909)
				)
				(xy 158.672276 -29.54909) (xy 158.672276 -3.9878)
			)
		)
	)
	(zone
		(layers "F.Cu" "B.Cu" "In1.Cu" "In2.Cu")
		(name "Route Keepin")
		(hatch none 0.5)
		(connect_pads
			(clearance 0)
		)
		(min_thickness 0.25)
		(keepout
			(tracks allowed)
			(vias allowed)
			(pads allowed)
			(copperpour allowed)
			(footprints allowed)
		)
		(placement
			(enabled no)
			(sheetname "")
		)
		(fill
			(thermal_gap 0.5)
			(thermal_bridge_width 0.5)
			(island_removal_mode 0)
		)
		(polygon
			(pts
				(arc
					(start 161.898076 -0.999998)
					(mid 161.828368 -0.831708)
					(end 161.660078 -0.762)
				)
				(arc
					(start 0.999998 -0.762)
					(mid 0.831708 -0.831708)
					(end 0.762 -0.999998)
				)
				(arc
					(start 0.762 -27.170126)
					(mid 0.245923 -28.416047)
					(end -0.999998 -28.932124)
				)
				(xy -9.184386 -28.932124) (xy -10.237978 -29.985716) (xy -10.237978 -72.364346) (xy -9.184386 -73.417938)
				(arc
					(start -0.350012 -73.417938)
					(mid 0.762 -74.52995)
					(end -0.350012 -75.641962)
				)
				(xy -9.184386 -75.641962) (xy -10.237978 -76.695554) (xy -10.237978 -91.134438) (xy -9.184386 -92.18803)
				(arc
					(start -0.999998 -92.18803)
					(mid 0.245923 -92.704107)
					(end 0.762 -93.950028)
				)
				(arc
					(start 0.762 -119.000016)
					(mid 0.831708 -119.168306)
					(end 0.999998 -119.238014)
				)
				(arc
					(start 161.660078 -119.238014)
					(mid 161.828368 -119.168306)
					(end 161.898076 -119.000016)
				)
				(arc
					(start 161.898076 -98.685096)
					(mid 161.869855 -98.572937)
					(end 161.792158 -98.48723)
				)
				(arc
					(start 159.488886 -96.952054)
					(mid 159.425944 -96.922218)
					(end 159.35706 -96.911922)
				)
				(arc
					(start 138.660124 -96.911922)
					(mid 137.414203 -96.395845)
					(end 136.898126 -95.149924)
				)
				(arc
					(start 136.898126 -90.849958)
					(mid 137.414203 -89.604037)
					(end 138.660124 -89.08796)
				)
				(arc
					(start 159.357314 -89.08796)
					(mid 159.426181 -89.077779)
					(end 159.48914 -89.048082)
				)
				(arc
					(start 161.792158 -87.512906)
					(mid 161.870014 -87.42714)
					(end 161.898076 -87.314786)
				)
				(arc
					(start 161.898076 -81.46288)
					(mid 161.828368 -81.29459)
					(end 161.660078 -81.224882)
				)
				(arc
					(start 158.660084 -81.224882)
					(mid 157.414163 -80.708805)
					(end 156.898086 -79.462884)
				)
				(arc
					(start 156.898086 -34.536888)
					(mid 157.414163 -33.290967)
					(end 158.660084 -32.77489)
				)
				(arc
					(start 161.660078 -32.77489)
					(mid 161.828368 -32.705182)
					(end 161.898076 -32.536892)
				)
			)
		)
	)
	(zone
		(layer "B.Cu")
		(hatch none 0.5)
		(connect_pads
			(clearance 0)
		)
		(min_thickness 0.25)
		(keepout
			(tracks allowed)
			(vias allowed)
			(pads allowed)
			(copperpour allowed)
			(footprints not_allowed)
		)
		(placement
			(enabled no)
			(sheetname "")
		)
		(fill
			(thermal_gap 0.5)
			(thermal_bridge_width 0.5)
			(island_removal_mode 0)
		)
		(polygon
			(pts
				(arc
					(start 154.159966 -114.000026)
					(mid 149.660102 -109.500162)
					(end 145.159984 -114.000026)
				)
				(arc
					(start 145.159984 -114.000026)
					(mid 149.660102 -118.500144)
					(end 154.159966 -114.000026)
				)
			)
		)
	)
	(zone
		(net "GND")
		(layer "B.Cu")
		(hatch none 0.5)
		(connect_pads
			(clearance 0.5)
		)
		(min_thickness 0.25)
		(fill yes
			(thermal_gap 0.5)
			(thermal_bridge_width 0.5)
			(island_removal_mode 0)
		)
		(polygon
			(pts
				(xy 161.518092 -119.236744) (xy 161.863024 -118.891812) (xy 161.863024 -98.563176) (xy 159.535114 -97.011744)
				(arc
					(start 138.658092 -97.011744)
					(mid 137.400856 -96.49098)
					(end 136.880092 -95.233744)
				)
				(arc
					(start 136.880092 -90.788744)
					(mid 137.400856 -89.531508)
					(end 138.658092 -89.010744)
				)
				(xy 159.507174 -89.010744) (xy 161.844482 -87.460836) (xy 161.844482 -81.534) (xy 161.590482 -81.28)
				(xy 157.861 -81.28) (xy 156.845 -80.264) (xy 156.845 -76.327) (xy 156.845 -53.467) (xy 156.845 -33.782)
				(xy 157.861 -32.766) (xy 161.544 -32.766) (xy 161.844482 -32.465518) (xy 161.844482 -28.448) (xy 161.844482 -0.989076)
				(xy 161.668968 -0.813562) (xy 1.112774 -0.813562) (xy 0.883666 -1.04267) (xy 0.883666 -15.731744)
				(xy 0.883666 -18.917666) (xy 0.889 -18.923) (xy 0.889 -19.939) (xy 1.016 -20.066) (xy 9.652 -20.066)
				(xy 10.7315 -18.9865) (xy 13.859256 -15.858744) (xy 128.244092 -15.858744) (xy 139.18184 -15.858744)
				(xy 150.622 -27.298904) (xy 150.622 -30.353) (xy 151.257 -30.988) (xy 152.527 -32.258) (xy 154.051 -32.258)
				(xy 154.432 -32.639) (xy 155.956 -34.163) (xy 155.956 -47.371) (xy 155.956 -52.324) (xy 154.813 -53.467)
				(xy 151.765 -53.467) (xy 149.86 -55.372) (xy 144.78 -55.372) (xy 144.399 -55.372) (xy 143.9545 -54.9275)
				(xy 143.9545 -54.1655) (xy 143.9545 -50.9905) (xy 143.891 -50.927) (xy 142.477744 -49.513744) (xy 140.716 -47.752)
				(xy 106.045 -47.752) (xy 104.283256 -49.513744) (xy 104.267 -49.513744) (xy -8.357108 -49.513744)
				(xy -8.458708 -49.615344) (xy -8.458708 -58.759344) (xy -8.306308 -58.911744) (xy -3.184652 -58.911744)
				(xy -3.140964 -58.955432) (xy -3.140964 -59.601862) (xy -3.19405 -59.654948) (xy -8.287512 -59.654948)
				(xy -8.433308 -59.800744) (xy -8.433308 -68.919344) (xy -8.282686 -69.069966) (xy -3.20294 -69.069966)
				(xy -3.165602 -69.107304) (xy -3.165602 -69.775832) (xy -3.204464 -69.814694) (xy -8.312658 -69.814694)
				(xy -8.433308 -69.935344) (xy -8.433308 -73.252076) (xy -8.269478 -73.415906) (xy 0.22606 -73.415906)
				(xy 0.863092 -74.052938) (xy 0.863092 -74.697082) (xy 0.863092 -75.675744) (xy 0.228092 -76.310744)
				(xy -0.914908 -76.310744) (xy -1.041908 -76.437744) (xy -1.041908 -76.945744) (xy -0.914908 -77.072744)
				(xy 12.801092 -77.072744) (xy 15.468092 -79.739744) (xy 15.468092 -94.725744) (xy 17.373092 -96.630744)
				(xy 22.072092 -96.630744) (xy 126.339092 -96.630744) (xy 127.101092 -95.868744) (xy 127.101092 -87.486744)
				(xy 135.991092 -78.596744) (xy 145.262092 -78.596744) (xy 145.770092 -79.104744) (xy 145.897092 -79.231744)
				(xy 145.897092 -81.263744) (xy 146.405092 -81.771744) (xy 155.549092 -81.771744) (xy 156.184092 -82.406744)
				(xy 156.184092 -87.486744) (xy 155.930092 -87.740744) (xy 135.737092 -87.740744) (xy 134.340092 -89.137744)
				(xy 134.340092 -97.138744) (xy 137.642092 -100.440744) (xy 155.803092 -100.440744) (xy 156.565092 -101.202744)
				(xy 156.565092 -103.488744) (xy 156.819092 -103.742744) (xy 157.962092 -103.742744) (xy 158.216092 -103.996744)
				(xy 158.216092 -105.266744) (xy 158.216092 -105.816908) (xy 156.480256 -107.552744) (xy 155.930092 -107.552744)
				(xy 132.079492 -107.552744) (xy 128.142492 -103.615744) (xy 16.865092 -103.615744) (xy 14.452092 -103.615744)
				(xy 12.446 -103.615744) (xy 11.641836 -103.615744) (xy 8.864092 -100.838) (xy 7.099046 -99.072954)
				(xy 6.832092 -98.806) (xy 6.832092 -91.677744) (xy 4.292092 -89.137744) (xy 0.872236 -89.137744)
				(xy 0.110236 -89.899744) (xy -0.787908 -89.899744) (xy -2.311908 -89.899744) (xy -2.565908 -90.153744)
				(xy -2.565908 -91.931744) (xy -2.438908 -92.058744)
				(arc
					(start -0.914908 -92.058744)
					(mid 0.334043 -92.496592)
					(end 0.863092 -93.709744)
				)
				(xy 0.863092 -118.855744) (xy 1.244092 -119.236744)
			)
		)
	)
	(zone
		(layer "B.Cu")
		(hatch none 0.5)
		(connect_pads
			(clearance 0)
		)
		(min_thickness 0.25)
		(keepout
			(tracks allowed)
			(vias allowed)
			(pads allowed)
			(copperpour allowed)
			(footprints not_allowed)
		)
		(placement
			(enabled no)
			(sheetname "")
		)
		(fill
			(thermal_gap 0.5)
			(thermal_bridge_width 0.5)
			(island_removal_mode 0)
		)
		(polygon
			(pts
				(arc
					(start 122.16003 -5.999988)
					(mid 126.660148 -10.500106)
					(end 131.160012 -5.999988)
				)
				(arc
					(start 131.160012 -5.999988)
					(mid 126.660148 -1.500124)
					(end 122.16003 -5.999988)
				)
			)
		)
	)
	(zone
		(net "P3V3")
		(layer "B.Cu")
		(hatch none 0.5)
		(connect_pads
			(clearance 0.5)
		)
		(min_thickness 0.25)
		(fill yes
			(thermal_gap 0.5)
			(thermal_bridge_width 0.5)
			(island_removal_mode 0)
		)
		(polygon
			(pts
				(xy 1.625092 -77.622654) (xy 0.135382 -77.622654) (xy -0.230378 -77.622654) (xy -0.799338 -77.622654)
				(xy -0.846074 -77.622654) (xy -4.440682 -77.622654) (xy -4.444746 -77.626718) (xy -7.87908 -77.626718)
				(xy -7.94131 -77.688948) (xy -7.94131 -78.367636) (xy -7.894574 -78.414372) (xy -4.49326 -78.414372)
				(xy -4.459224 -78.448408) (xy -4.459224 -78.880716) (xy -4.482338 -78.90383) (xy -7.900924 -78.90383)
				(xy -7.94131 -78.944216) (xy -7.94131 -79.570326) (xy -7.841742 -79.669894) (xy -4.507738 -79.669894)
				(xy -0.408178 -79.669894) (xy -0.108458 -79.969614) (xy 1.117092 -79.969614) (xy 2.728722 -81.581244)
				(xy 8.673592 -81.581244) (xy 11.531092 -84.438744) (xy 11.531092 -95.106744) (xy 9.144 -97.493836)
				(xy 9.144 -98.552) (xy 9.398 -98.806) (xy 10.303256 -98.806) (xy 10.795 -98.806) (xy 13.462 -101.473)
				(xy 13.572744 -101.583744) (xy 13.699744 -101.583744) (xy 15.595092 -101.583744) (xy 129.606548 -101.583744)
				(xy 133.086348 -105.063544) (xy 155.218892 -105.063544) (xy 155.752292 -105.063544) (xy 155.930092 -104.885744)
				(xy 155.930092 -101.456744) (xy 155.422092 -100.948744) (xy 137.261092 -100.948744) (xy 133.705092 -97.392744)
				(xy 133.705092 -89.010744) (xy 135.610092 -87.105744) (xy 136.372092 -87.105744) (xy 154.787092 -87.105744)
				(xy 155.231592 -86.661244) (xy 155.231592 -83.232244) (xy 155.231592 -82.851244) (xy 154.914092 -82.533744)
				(xy 146.151092 -82.533744) (xy 145.262092 -81.644744) (xy 145.262092 -79.612744) (xy 145.008092 -79.358744)
				(xy 136.372092 -79.358744) (xy 133.959092 -81.771744) (xy 129.514092 -86.216744) (xy 127.863092 -87.867744)
				(xy 127.863092 -96.757744) (xy 127.355092 -97.265744) (xy 21.564092 -97.265744) (xy 16.992092 -97.265744)
				(xy 14.960092 -95.233744) (xy 14.960092 -80.247744) (xy 12.335002 -77.622654) (xy 10.557002 -77.622654)
			)
		)
	)
	(zone
		(layer "B.Cu")
		(hatch none 0.5)
		(connect_pads
			(clearance 0)
		)
		(min_thickness 0.25)
		(keepout
			(tracks allowed)
			(vias allowed)
			(pads allowed)
			(copperpour allowed)
			(footprints not_allowed)
		)
		(placement
			(enabled no)
			(sheetname "")
		)
		(fill
			(thermal_gap 0.5)
			(thermal_bridge_width 0.5)
			(island_removal_mode 0)
		)
		(polygon
			(pts
				(xy 0 -3.999992) (xy 0 -116.000022) (xy 15.999968 -116.000022) (xy 15.999968 -3.999992)
			)
		)
	)
	(zone
		(layer "B.Cu")
		(hatch none 0.5)
		(connect_pads
			(clearance 0)
		)
		(min_thickness 0.25)
		(keepout
			(tracks allowed)
			(vias allowed)
			(pads allowed)
			(copperpour allowed)
			(footprints not_allowed)
		)
		(placement
			(enabled no)
			(sheetname "")
		)
		(fill
			(thermal_gap 0.5)
			(thermal_bridge_width 0.5)
			(island_removal_mode 0)
		)
		(polygon
			(pts
				(arc
					(start 145.159984 -114.000026)
					(mid 149.660102 -118.500144)
					(end 154.159966 -114.000026)
				)
				(arc
					(start 154.159966 -114.000026)
					(mid 149.660102 -109.500162)
					(end 145.159984 -114.000026)
				)
			)
		)
	)
	(zone
		(layer "B.Cu")
		(hatch none 0.5)
		(connect_pads
			(clearance 0)
		)
		(min_thickness 0.25)
		(keepout
			(tracks allowed)
			(vias allowed)
			(pads allowed)
			(copperpour allowed)
			(footprints not_allowed)
		)
		(placement
			(enabled no)
			(sheetname "")
		)
		(fill
			(thermal_gap 0.5)
			(thermal_bridge_width 0.5)
			(island_removal_mode 0)
		)
		(polygon
			(pts
				(arc
					(start 161.660078 -120.000014)
					(mid 162.367183 -119.707121)
					(end 162.660076 -119.000016)
				)
				(arc
					(start 162.660076 -98.685096)
					(mid 162.541691 -98.213381)
					(end 162.214814 -97.853246)
				)
				(arc
					(start 159.911796 -96.31807)
					(mid 159.647 -96.192958)
					(end 159.357314 -96.149922)
				)
				(arc
					(start 138.660124 -96.149922)
					(mid 137.953019 -95.857029)
					(end 137.660126 -95.149924)
				)
				(arc
					(start 137.660126 -90.849958)
					(mid 137.953019 -90.142853)
					(end 138.660124 -89.84996)
				)
				(arc
					(start 159.357314 -89.84996)
					(mid 159.646996 -89.807083)
					(end 159.911796 -89.682066)
				)
				(arc
					(start 162.214814 -88.14689)
					(mid 162.54181 -87.786674)
					(end 162.660076 -87.314786)
				)
				(arc
					(start 162.660076 -81.46288)
					(mid 162.367183 -80.755775)
					(end 161.660078 -80.462882)
				)
				(arc
					(start 158.660084 -80.462882)
					(mid 157.952979 -80.169989)
					(end 157.660086 -79.462884)
				)
				(arc
					(start 157.660086 -34.536888)
					(mid 157.952979 -33.829783)
					(end 158.660084 -33.53689)
				)
				(arc
					(start 161.660078 -33.53689)
					(mid 162.367183 -33.243997)
					(end 162.660076 -32.536892)
				)
				(arc
					(start 162.660076 -0.999998)
					(mid 162.367183 -0.292893)
					(end 161.660078 0)
				)
				(arc
					(start 0.999998 0)
					(mid 0.292893 -0.292893)
					(end 0 -0.999998)
				)
				(xy 0 -3.999992) (xy 15.999968 -3.999992) (xy 15.999968 -116.000022) (xy 0 -116.000022)
				(arc
					(start 0 -119.000016)
					(mid 0.292893 -119.707121)
					(end 0.999998 -120.000014)
				)
			)
		)
	)
	(zone
		(net "P12V")
		(layer "B.Cu")
		(hatch none 0.5)
		(connect_pads
			(clearance 0.5)
		)
		(min_thickness 0.25)
		(fill yes
			(thermal_gap 0.5)
			(thermal_bridge_width 0.5)
			(island_removal_mode 0)
		)
		(polygon
			(pts
				(xy 154.432 -45.466) (xy 154.432 -44.958) (xy 154.432 -41.148) (xy 149.987 -36.703) (xy 149.606 -36.322)
				(xy 149.606 -36.195) (xy 149.606 -27.051) (xy 138.921744 -16.366744) (xy 127.990092 -16.366744)
				(xy 14.351 -16.366744) (xy 11.159744 -19.558) (xy 10.143744 -20.574) (xy 9.889744 -20.828) (xy 1.498092 -20.828)
				(xy 0.863092 -21.463) (xy 0.863092 -22.352) (xy 0.863092 -23.097744) (xy 0.863092 -28.050744) (xy -0.233934 -29.14777)
				(xy -7.8359 -29.14777) (xy -7.839964 -29.152088) (xy -8.366252 -29.152088) (xy -8.458708 -29.244544)
				(xy -8.458708 -38.413944) (xy -8.291068 -38.581584) (xy -3.198876 -38.581584) (xy -3.130804 -38.649656)
				(xy -3.130804 -39.252906) (xy -3.21183 -39.333932) (xy -8.388096 -39.333932) (xy -8.458708 -39.404544)
				(xy -8.458708 -48.624744) (xy -8.325612 -48.75784) (xy 103.886 -48.75784) (xy 105.65384 -46.99)
				(xy 141.097 -46.99) (xy 144.145 -50.038) (xy 153.797 -50.038) (xy 154.432 -49.403) (xy 154.432 -48.514)
			)
		)
	)
	(zone
		(layer "B.Cu")
		(hatch none 0.5)
		(connect_pads
			(clearance 0)
		)
		(min_thickness 0.25)
		(keepout
			(tracks allowed)
			(vias allowed)
			(pads allowed)
			(copperpour allowed)
			(footprints not_allowed)
		)
		(placement
			(enabled no)
			(sheetname "")
		)
		(fill
			(thermal_gap 0.5)
			(thermal_bridge_width 0.5)
			(island_removal_mode 0)
		)
		(polygon
			(pts
				(arc
					(start 131.160012 -5.999988)
					(mid 126.660148 -1.500124)
					(end 122.16003 -5.999988)
				)
				(arc
					(start 122.16003 -5.999988)
					(mid 126.660148 -10.500106)
					(end 131.160012 -5.999988)
				)
			)
		)
	)
	(zone
		(net "GND")
		(layer "In1.Cu")
		(hatch none 0.5)
		(connect_pads
			(clearance 0.5)
		)
		(min_thickness 0.25)
		(fill yes
			(thermal_gap 0.5)
			(thermal_bridge_width 0.5)
			(island_removal_mode 0)
		)
		(polygon
			(pts
				(arc
					(start 0.999998 -0.763016)
					(mid 0.832426 -0.832426)
					(end 0.763016 -0.999998)
				)
				(xy 0.763016 -20.193) (xy 9.673844 -20.193) (xy 13.991844 -15.875) (xy 14.224 -15.875) (xy 139.154916 -15.85976)
				(xy 150.114 -26.818844) (xy 150.114 -36.089844) (xy 154.813 -40.788844) (xy 154.813 -49.635156)
				(xy 153.902156 -50.546) (xy 143.785844 -50.546) (xy 140.864844 -47.625) (xy 106.150156 -47.625)
				(xy 104.372156 -49.403) (xy -8.459978 -49.38776) (xy -8.459978 -73.416922)
				(arc
					(start -0.350012 -73.416922)
					(mid 0.763016 -74.52995)
					(end -0.350012 -75.642978)
				)
				(xy -8.459978 -75.642978) (xy -8.459978 -92.187014)
				(arc
					(start -0.999998 -92.187014)
					(mid 0.246641 -92.703389)
					(end 0.763016 -93.950028)
				)
				(arc
					(start 0.763016 -119.000016)
					(mid 0.832426 -119.167588)
					(end 0.999998 -119.236998)
				)
				(arc
					(start 161.660078 -119.236998)
					(mid 161.82765 -119.167588)
					(end 161.89706 -119.000016)
				)
				(arc
					(start 161.89706 -98.685096)
					(mid 161.869052 -98.573336)
					(end 161.79165 -98.487992)
				)
				(arc
					(start 159.488378 -96.952816)
					(mid 159.425669 -96.923162)
					(end 159.35706 -96.912938)
				)
				(arc
					(start 138.660124 -96.912938)
					(mid 137.413485 -96.396563)
					(end 136.89711 -95.149924)
				)
				(arc
					(start 136.89711 -90.849958)
					(mid 137.413485 -89.603319)
					(end 138.660124 -89.086944)
				)
				(arc
					(start 159.357314 -89.086944)
					(mid 159.425887 -89.076806)
					(end 159.488632 -89.04732)
				)
				(arc
					(start 161.79165 -87.512144)
					(mid 161.869113 -87.426688)
					(end 161.89706 -87.314786)
				)
				(arc
					(start 161.89706 -81.46288)
					(mid 161.82765 -81.295308)
					(end 161.660078 -81.225898)
				)
				(arc
					(start 158.660084 -81.225898)
					(mid 157.413445 -80.709523)
					(end 156.89707 -79.462884)
				)
				(arc
					(start 156.89707 -34.536888)
					(mid 157.413445 -33.290249)
					(end 158.660084 -32.773874)
				)
				(arc
					(start 161.660078 -32.773874)
					(mid 161.82765 -32.704464)
					(end 161.89706 -32.536892)
				)
				(arc
					(start 161.89706 -0.999998)
					(mid 161.82765 -0.832426)
					(end 161.660078 -0.763016)
				)
			)
		)
	)
	(zone
		(net "P12V")
		(layer "In1.Cu")
		(hatch none 0.5)
		(connect_pads
			(clearance 0.5)
		)
		(min_thickness 0.25)
		(fill yes
			(thermal_gap 0.5)
			(thermal_bridge_width 0.5)
			(island_removal_mode 0)
		)
		(polygon
			(pts
				(xy 138.944604 -16.36776) (xy 14.224 -16.383) (xy 14.202156 -16.383) (xy 9.884156 -20.701) (xy 0.763016 -20.701)
				(arc
					(start 0.763016 -27.170126)
					(mid 0.246641 -28.416765)
					(end -0.999998 -28.93314)
				)
				(xy -8.459978 -28.93314) (xy -8.459978 -48.87976) (xy 104.161844 -48.895) (xy 105.939844 -47.117)
				(xy 141.075156 -47.117) (xy 143.996156 -50.038) (xy 153.691844 -50.038) (xy 154.305 -49.424844)
				(xy 154.305 -40.999156) (xy 149.606 -36.300156) (xy 149.606 -27.029156)
			)
		)
	)
	(zone
		(net "P12V")
		(layer "In2.Cu")
		(hatch none 0.5)
		(connect_pads
			(clearance 0.5)
		)
		(min_thickness 0.25)
		(fill yes
			(thermal_gap 0.5)
			(thermal_bridge_width 0.5)
			(island_removal_mode 0)
		)
		(polygon
			(pts
				(xy 138.944604 -16.36776) (xy 14.224 -16.383) (xy 14.202156 -16.383) (xy 9.884156 -20.701) (xy 1.27 -20.701)
				(arc
					(start 1.27 -27.170126)
					(mid 0.605133 -28.775257)
					(end -0.999998 -29.440124)
				)
				(xy -8.459978 -29.440124) (xy -8.459978 -48.87976) (xy 104.161844 -48.895) (xy 105.93959 -47.117)
				(xy 123.670822 -47.10176) (xy 141.07541 -47.117) (xy 143.996156 -50.038) (xy 153.691844 -50.038)
				(xy 154.305 -49.424844) (xy 154.305 -40.999156) (xy 149.606 -36.300156) (xy 149.606 -27.029156)
			)
		)
	)
	(zone
		(net "GND")
		(layer "In2.Cu")
		(hatch none 0.5)
		(connect_pads
			(clearance 0.5)
		)
		(min_thickness 0.25)
		(fill yes
			(thermal_gap 0.5)
			(thermal_bridge_width 0.5)
			(island_removal_mode 0)
		)
		(polygon
			(pts
				(xy 1.27 -1.27) (xy 1.27 -20.193) (xy 9.673844 -20.193) (xy 13.991844 -15.875) (xy 14.224 -15.875)
				(xy 139.154916 -15.85976) (xy 150.114 -26.818844) (xy 150.114 -36.089844) (xy 154.813 -40.788844)
				(xy 154.813 -49.635156) (xy 153.902156 -50.546) (xy 143.785844 -50.546) (xy 140.86459 -47.625) (xy 123.670822 -47.60976)
				(xy 106.15041 -47.625) (xy 104.372156 -49.403) (xy -8.459978 -49.38776) (xy -8.459978 -72.909938)
				(arc
					(start -0.350012 -72.909938)
					(mid 1.27 -74.52995)
					(end -0.350012 -76.149962)
				)
				(xy -8.459978 -76.149962) (xy -8.459978 -91.68003)
				(arc
					(start -0.999998 -91.68003)
					(mid 0.605133 -92.344897)
					(end 1.27 -93.950028)
				)
				(xy 1.27 -118.730014) (xy 161.390076 -118.730014) (xy 161.390076 -98.829876) (xy 159.275018 -97.419922)
				(arc
					(start 138.660124 -97.419922)
					(mid 137.054993 -96.755055)
					(end 136.390126 -95.149924)
				)
				(arc
					(start 136.390126 -90.849958)
					(mid 137.054993 -89.244827)
					(end 138.660124 -88.57996)
				)
				(xy 159.275526 -88.57996) (xy 161.390076 -87.17026) (xy 161.390076 -81.225898)
				(arc
					(start 158.660084 -81.225898)
					(mid 157.413445 -80.709523)
					(end 156.89707 -79.462884)
				)
				(arc
					(start 156.89707 -34.536888)
					(mid 157.413445 -33.290249)
					(end 158.660084 -32.773874)
				)
				(xy 161.390076 -32.773874) (xy 161.390076 -1.27)
			)
		)
	)
)
